FILE_TYPE = MACRO_DRAWING;
SET COLOR_WIRE YELLOW;
SET COLOR_PROP ORANGE;
SET COLOR_DOT WHITE;
SET COLOR_ARC YELLOW;
SET COLOR_BODY GREEN;
SET COLOR_NOTE PURPLE;
SET PROP_DISPLAY VALUE;
SET PAGE_NUMBER P477;
FORCEADD UNIVERSAL_GND..1
R 5
(-7875 1775);
FORCEPROP 3 LASTPIN (-7825 1775) SIG_NAME GND\g
J 0
(-7815 1785);
DISPLAY 0.659574 (-7815 1785);
PAINT MONO (-7815 1785);
DISPLAY INVISIBLE (-7815 1785);
FORCEPROP 2 LAST CDS_LIB pure_quanta_power
J 0
(-7875 1775);
DISPLAY INVISIBLE (-7875 1775);
FORCEPROP 1 LAST HDL_POWER GND
R 3
J 1
(-7950 1750);
DISPLAY 0.872340 (-7950 1750);
PAINT GREEN (-7950 1750);
DISPLAY INVISIBLE (-7950 1750);
FORCEPROP 1 LAST PATH I1
R 3
J 0
(-7875 1700);
DISPLAY 0.872340 (-7875 1700);
PAINT AQUA (-7875 1700);
DISPLAY INVISIBLE (-7875 1700);
FORCEADD Q_RES..1
(-6300 725);
FORCEPROP 1 LAST LOCATION PR6809
J 0
(-6550 725);
DISPLAY 0.787234 (-6550 725);
FORCEPROP 0 LAST $SEC 1
J 0
(-6050 775);
DISPLAY 0.680851 (-6050 775);
PAINT MONO (-6050 775);
DISPLAY INVISIBLE (-6050 775);
FORCEPROP 0 LAST CDS_SEC 1
J 0
(-6050 775);
DISPLAY 0.680851 (-6050 775);
DISPLAY INVISIBLE (-6050 775);
FORCEPROP 1 LASTPIN (-6400 725) $PN 1
J 0
(-6388 737);
DISPLAY 0.787234 (-6388 737);
PAINT MONO (-6388 737);
FORCEPROP 1 LASTPIN (-6200 725) $PN 2
J 0
(-6238 737);
DISPLAY 0.787234 (-6238 737);
PAINT MONO (-6238 737);
FORCEPROP 1 LAST VALUE 0
J 2
(-6100 725);
DISPLAY 0.638298 (-6100 725);
FORCEPROP 1 LAST TOLERANCE 5%
J 0
(-6050 725);
DISPLAY 0.638298 (-6050 725);
FORCEPROP 1 LAST PACK_TYPE 0402LF
J 0
(-6150 850);
DISPLAY 0.510638 (-6150 850);
DISPLAY INVISIBLE (-6150 850);
FORCEPROP 1 LAST WATTAGE 1/16W
J 2
(-6175 850);
DISPLAY 0.510638 (-6175 850);
DISPLAY INVISIBLE (-6175 850);
FORCEPROP 1 LAST MATERIAL CHIP
J 0
(-6425 850);
DISPLAY 0.510638 (-6425 850);
DISPLAY INVISIBLE (-6425 850);
FORCEPROP 2 LAST CDS_LIB pure_quanta
J 0
(-6300 725);
DISPLAY INVISIBLE (-6300 725);
FORCEPROP 1 LAST PATH I10
J 0
(-6350 875);
DISPLAY 0.978723 (-6350 875);
PAINT WHITE (-6350 875);
DISPLAY INVISIBLE (-6350 875);
FORCEPROP 1 LAST PART_NUMBER CS00002JB13
J 0
(-6425 800);
DISPLAY 0.510638 (-6425 800);
DISPLAY INVISIBLE (-6425 800);
FORCEADD Q_RES..1
(-6300 825);
FORCEPROP 1 LAST LOCATION PR6808
J 0
(-6550 825);
DISPLAY 0.787234 (-6550 825);
FORCEPROP 0 LAST $SEC 1
J 0
(-6350 950);
DISPLAY 0.680851 (-6350 950);
PAINT MONO (-6350 950);
DISPLAY INVISIBLE (-6350 950);
FORCEPROP 0 LAST CDS_SEC 1
J 0
(-6350 950);
DISPLAY 0.680851 (-6350 950);
DISPLAY INVISIBLE (-6350 950);
FORCEPROP 1 LASTPIN (-6400 825) $PN 1
J 0
(-6388 837);
DISPLAY 0.787234 (-6388 837);
PAINT MONO (-6388 837);
FORCEPROP 1 LASTPIN (-6200 825) $PN 2
J 0
(-6238 837);
DISPLAY 0.787234 (-6238 837);
PAINT MONO (-6238 837);
FORCEPROP 1 LAST VALUE 0
J 2
(-6100 825);
DISPLAY 0.638298 (-6100 825);
FORCEPROP 1 LAST TOLERANCE 5%
J 0
(-6050 825);
DISPLAY 0.638298 (-6050 825);
FORCEPROP 1 LAST MATERIAL EMPTY
J 0
(-6350 900);
DISPLAY 0.638298 (-6350 900);
FORCEPROP 1 LAST PACK_TYPE 0402LF
J 0
(-6050 1000);
DISPLAY 0.638298 (-6050 1000);
DISPLAY INVISIBLE (-6050 1000);
FORCEPROP 1 LAST WATTAGE 1/16W
J 2
(-6100 1000);
DISPLAY 0.638298 (-6100 1000);
DISPLAY INVISIBLE (-6100 1000);
FORCEPROP 2 LAST CDS_LIB pure_quanta
J 0
(-6300 825);
DISPLAY INVISIBLE (-6300 825);
FORCEPROP 1 LAST PATH I11
J 0
(-6350 975);
DISPLAY 0.978723 (-6350 975);
PAINT WHITE (-6350 975);
DISPLAY INVISIBLE (-6350 975);
FORCEPROP 1 LAST PART_NUMBER CS00002JB13
J 0
(-6425 925);
DISPLAY 0.638298 (-6425 925);
DISPLAY INVISIBLE (-6425 925);
FORCEADD UNIVERSAL_GND..1
(-6100 975);
FORCEPROP 3 LASTPIN (-6100 1025) SIG_NAME GND\g
J 0
(-6090 1035);
DISPLAY 0.659574 (-6090 1035);
PAINT MONO (-6090 1035);
DISPLAY INVISIBLE (-6090 1035);
FORCEPROP 2 LAST CDS_LIB pure_quanta_power
J 0
(-6100 975);
DISPLAY INVISIBLE (-6100 975);
FORCEPROP 1 LAST HDL_POWER GND
J 1
(-6075 900);
DISPLAY 0.872340 (-6075 900);
PAINT GREEN (-6075 900);
DISPLAY INVISIBLE (-6075 900);
FORCEPROP 1 LAST PATH I12
J 0
(-6025 975);
DISPLAY 0.872340 (-6025 975);
PAINT AQUA (-6025 975);
DISPLAY INVISIBLE (-6025 975);
FORCEADD Q_RES..1
(-5750 1075);
FORCEPROP 1 LAST LOCATION PR6533
J 0
(-6000 1075);
DISPLAY 0.787234 (-6000 1075);
FORCEPROP 0 LAST $SEC 1
J 0
(-6000 1125);
DISPLAY 0.680851 (-6000 1125);
PAINT MONO (-6000 1125);
DISPLAY INVISIBLE (-6000 1125);
FORCEPROP 0 LAST CDS_SEC 1
J 0
(-6000 1125);
DISPLAY 0.680851 (-6000 1125);
DISPLAY INVISIBLE (-6000 1125);
FORCEPROP 1 LASTPIN (-5850 1075) $PN 1
J 0
(-5838 1087);
DISPLAY 0.787234 (-5838 1087);
PAINT MONO (-5838 1087);
FORCEPROP 1 LASTPIN (-5650 1075) $PN 2
J 0
(-5688 1087);
DISPLAY 0.787234 (-5688 1087);
PAINT MONO (-5688 1087);
FORCEPROP 1 LAST VALUE 22.1K
J 2
(-5775 1000);
DISPLAY 0.638298 (-5775 1000);
FORCEPROP 1 LAST TOLERANCE 1%
J 0
(-5725 1000);
DISPLAY 0.638298 (-5725 1000);
FORCEPROP 2 LASTPIN (-5650 1075) SIG_NAME P0V9_RETIMER_CPU1_ADDR
J 0
(-5660 1085);
DISPLAY 0.617021 (-5660 1085);
FORCEPROP 2 LASTPROP $XRERR UNIQUE?
J 0
(-5900 1085);
DISPLAY 0.638298 (-5900 1085);
PAINT MONO (-5900 1085);
DISPLAY INVISIBLE (-5900 1085);
FORCEPROP 2 LAST CDS_LIB pure_quanta
J 0
(-5750 1075);
DISPLAY INVISIBLE (-5750 1075);
FORCEPROP 1 LAST PACK_TYPE 0402LF
J 0
(-5600 1200);
DISPLAY 0.510638 (-5600 1200);
DISPLAY INVISIBLE (-5600 1200);
FORCEPROP 1 LAST MATERIAL CHIP
J 0
(-5875 1200);
DISPLAY 0.510638 (-5875 1200);
DISPLAY INVISIBLE (-5875 1200);
FORCEPROP 1 LAST WATTAGE 1/16W
J 2
(-5625 1200);
DISPLAY 0.510638 (-5625 1200);
DISPLAY INVISIBLE (-5625 1200);
FORCEPROP 1 LAST PATH I13
J 0
(-5800 1225);
DISPLAY 0.978723 (-5800 1225);
PAINT WHITE (-5800 1225);
DISPLAY INVISIBLE (-5800 1225);
FORCEPROP 1 LAST PART_NUMBER CS32212FB02
J 0
(-5900 950);
DISPLAY 0.510638 (-5900 950);
DISPLAY INVISIBLE (-5900 950);
FORCEADD Q_RES..2
R 2
(-6300 2375);
FORCEPROP 1 LAST LOCATION R665
J 2
(-6325 2475);
DISPLAY 0.808511 (-6325 2475);
FORCEPROP 0 LAST $SEC 1
J 0
(-6325 2525);
DISPLAY 0.680851 (-6325 2525);
PAINT MONO (-6325 2525);
DISPLAY INVISIBLE (-6325 2525);
FORCEPROP 0 LAST CDS_SEC 1
J 0
(-6325 2525);
DISPLAY 0.680851 (-6325 2525);
DISPLAY INVISIBLE (-6325 2525);
FORCEPROP 1 LASTPIN (-6300 2475) $PN 1
J 2
(-6305 2437);
DISPLAY 0.787234 (-6305 2437);
PAINT MONO (-6305 2437);
FORCEPROP 1 LASTPIN (-6300 2275) $PN 2
J 2
(-6305 2285);
DISPLAY 0.787234 (-6305 2285);
PAINT MONO (-6305 2285);
FORCEPROP 1 LAST WATTAGE 1/16W
J 2
(-6350 2325);
DISPLAY 0.510638 (-6350 2325);
FORCEPROP 1 LAST TOLERANCE 1%
J 2
(-6355 2375);
DISPLAY 0.510638 (-6355 2375);
FORCEPROP 1 LAST VALUE 1K
J 2
(-6355 2425);
DISPLAY 0.510638 (-6355 2425);
FORCEPROP 1 LAST MATERIAL CHIP
J 2
(-6350 2275);
DISPLAY 0.510638 (-6350 2275);
FORCEPROP 1 LAST PACK_TYPE 0402LF
J 2
(-6350 2175);
DISPLAY 0.510638 (-6350 2175);
FORCEPROP 2 LAST CDS_LIB pure_quanta
J 0
(-6300 2375);
DISPLAY INVISIBLE (-6300 2375);
FORCEPROP 1 LAST PATH I14
J 2
(-6350 2550);
DISPLAY 0.978723 (-6350 2550);
PAINT WHITE (-6350 2550);
DISPLAY INVISIBLE (-6350 2550);
FORCEPROP 1 LAST PART_NUMBER CS21002FB06
J 2
(-6350 2225);
DISPLAY 0.510638 (-6350 2225);
DISPLAY INVISIBLE (-6350 2225);
FORCEADD Q_RES..2
R 2
(-5925 2375);
FORCEPROP 1 LAST LOCATION R663
J 2
(-5980 2475);
DISPLAY 0.808511 (-5980 2475);
FORCEPROP 0 LAST $SEC 1
J 0
(-5975 2525);
DISPLAY 0.680851 (-5975 2525);
PAINT MONO (-5975 2525);
DISPLAY INVISIBLE (-5975 2525);
FORCEPROP 0 LAST CDS_SEC 1
J 0
(-5975 2525);
DISPLAY 0.680851 (-5975 2525);
DISPLAY INVISIBLE (-5975 2525);
FORCEPROP 1 LASTPIN (-5925 2475) $PN 1
J 2
(-5930 2437);
DISPLAY 0.787234 (-5930 2437);
PAINT MONO (-5930 2437);
FORCEPROP 1 LASTPIN (-5925 2275) $PN 2
J 2
(-5930 2285);
DISPLAY 0.787234 (-5930 2285);
PAINT MONO (-5930 2285);
FORCEPROP 1 LAST PACK_TYPE 0402LF
J 2
(-5975 2175);
DISPLAY 0.510638 (-5975 2175);
FORCEPROP 1 LAST WATTAGE 1/16W
J 2
(-5975 2325);
DISPLAY 0.510638 (-5975 2325);
FORCEPROP 1 LAST VALUE 1K
J 2
(-5980 2425);
DISPLAY 0.510638 (-5980 2425);
FORCEPROP 1 LAST TOLERANCE 1%
J 2
(-5980 2375);
DISPLAY 0.510638 (-5980 2375);
FORCEPROP 1 LAST MATERIAL CHIP
J 2
(-5975 2275);
DISPLAY 0.510638 (-5975 2275);
FORCEPROP 2 LAST CDS_LIB pure_quanta
J 0
(-5925 2375);
DISPLAY INVISIBLE (-5925 2375);
FORCEPROP 1 LAST PATH I15
J 2
(-5975 2550);
DISPLAY 0.978723 (-5975 2550);
PAINT WHITE (-5975 2550);
DISPLAY INVISIBLE (-5975 2550);
FORCEPROP 1 LAST PART_NUMBER CS21002FB06
J 2
(-5975 2225);
DISPLAY 0.510638 (-5975 2225);
DISPLAY INVISIBLE (-5975 2225);
FORCEADD UNIVERSAL_GND..1
(-8050 3550);
FORCEPROP 3 LASTPIN (-8050 3600) SIG_NAME GND\g
J 0
(-8040 3610);
DISPLAY 0.659574 (-8040 3610);
PAINT MONO (-8040 3610);
DISPLAY INVISIBLE (-8040 3610);
FORCEPROP 2 LAST CDS_LIB pure_quanta_power
J 0
(-8050 3550);
DISPLAY INVISIBLE (-8050 3550);
FORCEPROP 1 LAST HDL_POWER GND
J 1
(-8025 3475);
DISPLAY 0.872340 (-8025 3475);
PAINT GREEN (-8025 3475);
DISPLAY INVISIBLE (-8025 3475);
FORCEPROP 1 LAST PATH I16
J 0
(-7975 3550);
DISPLAY 0.872340 (-7975 3550);
PAINT AQUA (-7975 3550);
DISPLAY INVISIBLE (-7975 3550);
FORCEADD VCC15..1
(-8050 4475);
FORCEPROP 3 LASTPIN (-8050 4425) SIG_NAME P0V9_CPU1_RT_2D\g
J 0
(-8040 4435);
DISPLAY 0.659574 (-8040 4435);
PAINT MONO (-8040 4435);
DISPLAY INVISIBLE (-8040 4435);
FORCEPROP 1 LAST HDL_POWER P0V9_CPU1_RT_2D
J 1
(-8050 4525);
DISPLAY 0.617021 (-8050 4525);
PAINT GREEN (-8050 4525);
FORCEPROP 2 LAST CDS_LIB pure_quanta_power
J 0
(-8050 4475);
DISPLAY INVISIBLE (-8050 4475);
FORCEPROP 1 LAST PATH I17
J 0
(-8000 4500);
DISPLAY 0.872340 (-8000 4500);
PAINT AQUA (-8000 4500);
DISPLAY INVISIBLE (-8000 4500);
FORCEADD Q_RES..1
(-7350 1775);
FORCEPROP 1 LAST LOCATION R6800
J 0
(-7400 1825);
DISPLAY 0.978723 (-7400 1825);
FORCEPROP 0 LAST $SEC 1
J 0
(-7400 1875);
DISPLAY 0.680851 (-7400 1875);
PAINT MONO (-7400 1875);
DISPLAY INVISIBLE (-7400 1875);
FORCEPROP 0 LAST CDS_SEC 1
J 0
(-7400 1875);
DISPLAY 0.680851 (-7400 1875);
DISPLAY INVISIBLE (-7400 1875);
FORCEPROP 1 LASTPIN (-7450 1775) $PN 1
J 0
(-7438 1787);
DISPLAY 0.787234 (-7438 1787);
PAINT MONO (-7438 1787);
FORCEPROP 1 LASTPIN (-7250 1775) $PN 2
J 0
(-7288 1787);
DISPLAY 0.787234 (-7288 1787);
PAINT MONO (-7288 1787);
FORCEPROP 1 LAST MATERIAL CHIP
J 0
(-7475 1700);
DISPLAY 0.638298 (-7475 1700);
FORCEPROP 1 LAST WATTAGE 1/16W
J 2
(-7150 1700);
DISPLAY 0.638298 (-7150 1700);
FORCEPROP 1 LAST PACK_TYPE 0402LF
J 0
(-7125 1700);
DISPLAY 0.638298 (-7125 1700);
FORCEPROP 1 LAST TOLERANCE 5%
J 0
(-7075 1775);
DISPLAY 0.510638 (-7075 1775);
FORCEPROP 1 LAST VALUE 0
J 2
(-7125 1775);
DISPLAY 0.510638 (-7125 1775);
FORCEPROP 2 LAST CDS_LIB pure_quanta
J 0
(-7350 1775);
DISPLAY INVISIBLE (-7350 1775);
FORCEPROP 1 LAST PATH I2
J 0
(-7400 1925);
DISPLAY 0.978723 (-7400 1925);
PAINT WHITE (-7400 1925);
DISPLAY INVISIBLE (-7400 1925);
FORCEPROP 1 LAST PART_NUMBER CS00002JB13
J 0
(-7475 1650);
DISPLAY 0.638298 (-7475 1650);
DISPLAY INVISIBLE (-7475 1650);
FORCEADD OFFPAGE..1
(-7850 6025);
FORCEPROP 2 LAST $XR0 81 
J 0
(-8101 6025);
DISPLAY 0.638298 (-8101 6025);
PAINT MONO (-8101 6025);
FORCEPROP 2 LAST CDS_LIB standard
J 0
(-7850 6025);
DISPLAY INVISIBLE (-7850 6025);
FORCEPROP 1 LAST OFFPAGE TRUE
J 0
(-7525 5900);
DISPLAY 0.872340 (-7525 5900);
PAINT GREEN (-7525 5900);
DISPLAY INVISIBLE (-7525 5900);
FORCEPROP 1 LAST COMMENT_BODY TRUE
J 0
(-7725 5925);
DISPLAY 0.872340 (-7725 5925);
PAINT GREEN (-7725 5925);
DISPLAY INVISIBLE (-7725 5925);
FORCEPROP 2 LAST PATH I20
J 0
(-7800 6100);
DISPLAY 0.680851 (-7800 6100);
DISPLAY INVISIBLE (-7800 6100);
FORCEADD OFFPAGE..5
(-8575 6175);
FORCEPROP 2 LAST $XR0 81 
J 0
(-8829 6175);
DISPLAY 0.638298 (-8829 6175);
PAINT MONO (-8829 6175);
FORCEPROP 2 LAST CDS_LIB standard
J 0
(-8575 6175);
DISPLAY INVISIBLE (-8575 6175);
FORCEPROP 1 LAST OFFPAGE TRUE
J 0
(-8250 6050);
DISPLAY 0.872340 (-8250 6050);
PAINT GREEN (-8250 6050);
DISPLAY INVISIBLE (-8250 6050);
FORCEPROP 1 LAST COMMENT_BODY TRUE
J 0
(-8475 6100);
DISPLAY 0.872340 (-8475 6100);
PAINT GREEN (-8475 6100);
DISPLAY INVISIBLE (-8475 6100);
FORCEPROP 2 LAST PATH I21
J 0
(-8525 6250);
DISPLAY 0.680851 (-8525 6250);
DISPLAY INVISIBLE (-8525 6250);
FORCEADD Q_RES..1
(-7175 3650);
FORCEPROP 1 LAST LOCATION PR6602
J 0
(-7425 3650);
DISPLAY 0.765957 (-7425 3650);
FORCEPROP 0 LAST $SEC 1
J 0
(-6800 3800);
DISPLAY 0.680851 (-6800 3800);
PAINT MONO (-6800 3800);
DISPLAY INVISIBLE (-6800 3800);
FORCEPROP 0 LAST CDS_SEC 1
J 0
(-6800 3800);
DISPLAY 0.680851 (-6800 3800);
DISPLAY INVISIBLE (-6800 3800);
FORCEPROP 1 LASTPIN (-7275 3650) $PN 1
J 0
(-7263 3662);
DISPLAY 0.787234 (-7263 3662);
PAINT MONO (-7263 3662);
FORCEPROP 1 LASTPIN (-7075 3650) $PN 2
J 0
(-7113 3662);
DISPLAY 0.787234 (-7113 3662);
PAINT MONO (-7113 3662);
FORCEPROP 1 LAST WATTAGE 1/16W
J 2
(-6800 3750);
DISPLAY 0.617021 (-6800 3750);
FORCEPROP 1 LAST MATERIAL CHIP
J 0
(-7050 3750);
DISPLAY 0.617021 (-7050 3750);
FORCEPROP 1 LAST PACK_TYPE 0402LF
J 0
(-6875 3650);
DISPLAY 0.617021 (-6875 3650);
FORCEPROP 1 LAST TOLERANCE 1%
J 0
(-6950 3650);
DISPLAY 0.617021 (-6950 3650);
FORCEPROP 1 LAST VALUE 49.9
J 2
(-6975 3650);
DISPLAY 0.617021 (-6975 3650);
FORCEPROP 2 LAST CDS_LIB pure_quanta
J 0
(-7175 3650);
DISPLAY INVISIBLE (-7175 3650);
FORCEPROP 1 LAST PATH I22
J 0
(-7225 3800);
DISPLAY 0.978723 (-7225 3800);
PAINT WHITE (-7225 3800);
DISPLAY INVISIBLE (-7225 3800);
FORCEPROP 1 LAST PART_NUMBER CS04992FB07
J 0
(-7050 3700);
DISPLAY 0.617021 (-7050 3700);
DISPLAY INVISIBLE (-7050 3700);
FORCEADD Q_RES..1
(-7125 4325);
FORCEPROP 1 LAST LOCATION PR6600
J 0
(-7425 4325);
DISPLAY 0.765957 (-7425 4325);
FORCEPROP 0 LAST $SEC 1
J 0
(-6750 4475);
DISPLAY 0.680851 (-6750 4475);
PAINT MONO (-6750 4475);
DISPLAY INVISIBLE (-6750 4475);
FORCEPROP 0 LAST CDS_SEC 1
J 0
(-6750 4475);
DISPLAY 0.680851 (-6750 4475);
DISPLAY INVISIBLE (-6750 4475);
FORCEPROP 1 LASTPIN (-7225 4325) $PN 1
J 0
(-7213 4337);
DISPLAY 0.787234 (-7213 4337);
PAINT MONO (-7213 4337);
FORCEPROP 1 LASTPIN (-7025 4325) $PN 2
J 0
(-7063 4337);
DISPLAY 0.787234 (-7063 4337);
PAINT MONO (-7063 4337);
FORCEPROP 1 LAST PACK_TYPE 0402LF
J 0
(-6825 4325);
DISPLAY 0.617021 (-6825 4325);
FORCEPROP 1 LAST TOLERANCE 1%
J 0
(-6900 4325);
DISPLAY 0.617021 (-6900 4325);
FORCEPROP 1 LAST VALUE 49.9
J 2
(-6925 4325);
DISPLAY 0.617021 (-6925 4325);
FORCEPROP 1 LAST MATERIAL CHIP
J 0
(-7000 4425);
DISPLAY 0.617021 (-7000 4425);
FORCEPROP 1 LAST WATTAGE 1/16W
J 2
(-6750 4425);
DISPLAY 0.617021 (-6750 4425);
FORCEPROP 2 LAST CDS_LIB pure_quanta
J 0
(-7125 4325);
DISPLAY INVISIBLE (-7125 4325);
FORCEPROP 1 LAST PATH I23
J 0
(-7175 4475);
DISPLAY 0.978723 (-7175 4475);
PAINT WHITE (-7175 4475);
DISPLAY INVISIBLE (-7175 4475);
FORCEPROP 1 LAST PART_NUMBER CS04992FB07
J 0
(-7000 4375);
DISPLAY 0.617021 (-7000 4375);
DISPLAY INVISIBLE (-7000 4375);
FORCEADD UNIVERSAL_GND..1
(-6650 3550);
FORCEPROP 3 LASTPIN (-6650 3600) SIG_NAME GND\g
J 0
(-6640 3610);
DISPLAY 0.659574 (-6640 3610);
PAINT MONO (-6640 3610);
DISPLAY INVISIBLE (-6640 3610);
FORCEPROP 2 LAST CDS_LIB pure_quanta_power
J 0
(-6650 3550);
DISPLAY INVISIBLE (-6650 3550);
FORCEPROP 1 LAST HDL_POWER GND
J 1
(-6625 3475);
DISPLAY 0.872340 (-6625 3475);
PAINT GREEN (-6625 3475);
DISPLAY INVISIBLE (-6625 3475);
FORCEPROP 1 LAST PATH I24
J 0
(-6575 3550);
DISPLAY 0.872340 (-6575 3550);
PAINT AQUA (-6575 3550);
DISPLAY INVISIBLE (-6575 3550);
FORCEADD VCC15..1
(-6625 4475);
FORCEPROP 3 LASTPIN (-6625 4425) SIG_NAME P0V9_CPU1_RT_2D\g
J 0
(-6615 4435);
DISPLAY 0.659574 (-6615 4435);
PAINT MONO (-6615 4435);
DISPLAY INVISIBLE (-6615 4435);
FORCEPROP 1 LAST HDL_POWER P0V9_CPU1_RT_2D
J 1
(-6625 4525);
DISPLAY 0.617021 (-6625 4525);
PAINT GREEN (-6625 4525);
FORCEPROP 2 LAST CDS_LIB pure_quanta_power
J 0
(-6625 4475);
DISPLAY INVISIBLE (-6625 4475);
FORCEPROP 1 LAST PATH I25
J 0
(-6575 4500);
DISPLAY 0.872340 (-6575 4500);
PAINT AQUA (-6575 4500);
DISPLAY INVISIBLE (-6575 4500);
FORCEADD VCC15..1
(-6300 2600);
FORCEPROP 3 LASTPIN (-6300 2550) SIG_NAME P3V3_AUX\g
J 0
(-6290 2560);
DISPLAY 0.659574 (-6290 2560);
PAINT MONO (-6290 2560);
DISPLAY INVISIBLE (-6290 2560);
FORCEPROP 1 LAST HDL_POWER P3V3_AUX
J 1
(-6300 2650);
DISPLAY 0.617021 (-6300 2650);
PAINT GREEN (-6300 2650);
FORCEPROP 2 LAST CDS_LIB pure_quanta_power
J 0
(-6300 2600);
DISPLAY INVISIBLE (-6300 2600);
FORCEPROP 1 LAST PATH I26
J 0
(-6250 2625);
DISPLAY 0.872340 (-6250 2625);
PAINT AQUA (-6250 2625);
DISPLAY INVISIBLE (-6250 2625);
FORCEADD Q_RES..1
(-6100 4175);
FORCEPROP 1 LAST LOCATION PR6601
J 0
(-6350 4175);
DISPLAY 0.787234 (-6350 4175);
FORCEPROP 0 LAST $SEC 1
J 0
(-6350 4225);
DISPLAY 0.680851 (-6350 4225);
PAINT MONO (-6350 4225);
DISPLAY INVISIBLE (-6350 4225);
FORCEPROP 0 LAST CDS_SEC 1
J 0
(-6350 4225);
DISPLAY 0.680851 (-6350 4225);
DISPLAY INVISIBLE (-6350 4225);
FORCEPROP 1 LASTPIN (-6200 4175) $PN 1
J 0
(-6188 4187);
DISPLAY 0.787234 (-6188 4187);
PAINT MONO (-6188 4187);
FORCEPROP 1 LASTPIN (-6000 4175) $PN 2
J 0
(-6038 4187);
DISPLAY 0.787234 (-6038 4187);
PAINT MONO (-6038 4187);
FORCEPROP 1 LAST VALUE 0
J 2
(-6150 4100);
DISPLAY 0.510638 (-6150 4100);
FORCEPROP 1 LAST TOLERANCE 5%
J 0
(-6075 4100);
DISPLAY 0.510638 (-6075 4100);
FORCEPROP 1 LAST MATERIAL CHIP
J 0
(-6225 4300);
DISPLAY 0.510638 (-6225 4300);
DISPLAY INVISIBLE (-6225 4300);
FORCEPROP 1 LAST WATTAGE 1/16W
J 2
(-5975 4300);
DISPLAY 0.510638 (-5975 4300);
DISPLAY INVISIBLE (-5975 4300);
FORCEPROP 1 LAST PACK_TYPE 0402LF
J 0
(-5950 4300);
DISPLAY 0.510638 (-5950 4300);
DISPLAY INVISIBLE (-5950 4300);
FORCEPROP 2 LAST CDS_LIB pure_quanta
J 0
(-6100 4175);
DISPLAY INVISIBLE (-6100 4175);
FORCEPROP 1 LAST PATH I27
J 0
(-6150 4325);
DISPLAY 0.978723 (-6150 4325);
PAINT WHITE (-6150 4325);
DISPLAY INVISIBLE (-6150 4325);
FORCEPROP 1 LAST PART_NUMBER CS00002JB13
J 0
(-6225 4250);
DISPLAY 0.510638 (-6225 4250);
DISPLAY INVISIBLE (-6225 4250);
FORCEADD Q_CAP..1
(-5650 4000);
FORCEPROP 1 LAST LOCATION PC6600
J 0
(-5600 4100);
DISPLAY 0.808511 (-5600 4100);
FORCEPROP 0 LAST $SEC 1
J 0
(-5600 4150);
DISPLAY 0.680851 (-5600 4150);
PAINT MONO (-5600 4150);
DISPLAY INVISIBLE (-5600 4150);
FORCEPROP 0 LAST CDS_SEC 1
J 0
(-5600 4150);
DISPLAY 0.680851 (-5600 4150);
DISPLAY INVISIBLE (-5600 4150);
FORCEPROP 1 LASTPIN (-5650 4100) $PN 1
J 0
(-5640 4080);
DISPLAY 0.787234 (-5640 4080);
PAINT MONO (-5640 4080);
FORCEPROP 1 LASTPIN (-5650 3900) $PN 2
J 0
(-5640 3880);
DISPLAY 0.787234 (-5640 3880);
PAINT MONO (-5640 3880);
FORCEPROP 1 LAST TOLERANCE 10%
J 0
(-5600 3950);
DISPLAY 0.510638 (-5600 3950);
FORCEPROP 1 LAST MATERIAL X7R
J 0
(-5600 3900);
DISPLAY 0.510638 (-5600 3900);
FORCEPROP 1 LAST PACK_TYPE 0402
J 0
(-5600 3800);
DISPLAY 0.510638 (-5600 3800);
FORCEPROP 1 LAST VOLTAGE 50V
J 0
(-5600 4000);
DISPLAY 0.510638 (-5600 4000);
FORCEPROP 1 LAST VALUE 3300PF
J 0
(-5600 4050);
DISPLAY 0.510638 (-5600 4050);
FORCEPROP 2 LAST CDS_LIB pure_quanta
J 0
(-5650 4000);
DISPLAY INVISIBLE (-5650 4000);
FORCEPROP 1 LAST PATH I28
J 0
(-5600 4150);
DISPLAY 0.978723 (-5600 4150);
PAINT WHITE (-5600 4150);
DISPLAY INVISIBLE (-5600 4150);
FORCEPROP 1 LAST PART_NUMBER TMP_QCH2336K1B12
J 0
(-5600 3850);
DISPLAY 0.510638 (-5600 3850);
DISPLAY INVISIBLE (-5600 3850);
FORCEADD OFFPAGE..6
(-8250 4875);
FORCEPROP 2 LAST $XR0 151 
J 0
(-8530 4875);
DISPLAY 0.638298 (-8530 4875);
PAINT MONO (-8530 4875);
FORCEPROP 2 LAST CDS_LIB standard
J 0
(-8250 4875);
DISPLAY INVISIBLE (-8250 4875);
FORCEPROP 1 LAST OFFPAGE TRUE
J 0
(-7925 4750);
DISPLAY 0.872340 (-7925 4750);
PAINT GREEN (-7925 4750);
DISPLAY INVISIBLE (-7925 4750);
FORCEPROP 1 LAST COMMENT_BODY TRUE
J 0
(-8150 4800);
DISPLAY 0.872340 (-8150 4800);
PAINT GREEN (-8150 4800);
DISPLAY INVISIBLE (-8150 4800);
FORCEPROP 2 LAST PATH I29
J 0
(-8200 4950);
DISPLAY 0.680851 (-8200 4950);
DISPLAY INVISIBLE (-8200 4950);
FORCEADD Q_RES..2
R 2
(-6000 400);
FORCEPROP 1 LAST LOCATION PR6821
J 2
(-6045 525);
DISPLAY 0.787234 (-6045 525);
FORCEPROP 0 LAST $SEC 1
J 0
(-6025 575);
DISPLAY 0.680851 (-6025 575);
PAINT MONO (-6025 575);
DISPLAY INVISIBLE (-6025 575);
FORCEPROP 0 LAST CDS_SEC 1
J 0
(-6025 575);
DISPLAY 0.680851 (-6025 575);
DISPLAY INVISIBLE (-6025 575);
FORCEPROP 1 LASTPIN (-6000 500) $PN 1
J 2
(-6005 462);
DISPLAY 0.787234 (-6005 462);
PAINT MONO (-6005 462);
FORCEPROP 1 LASTPIN (-6000 300) $PN 2
J 2
(-6005 310);
DISPLAY 0.787234 (-6005 310);
PAINT MONO (-6005 310);
FORCEPROP 1 LAST WATTAGE 1/16W
J 2
(-6040 375);
DISPLAY 0.510638 (-6040 375);
FORCEPROP 1 LAST MATERIAL CHIP
J 2
(-6040 325);
DISPLAY 0.510638 (-6040 325);
FORCEPROP 1 LAST PACK_TYPE 0402LF
J 2
(-6040 225);
DISPLAY 0.510638 (-6040 225);
FORCEPROP 1 LAST VALUE 0
J 2
(-6045 475);
DISPLAY 0.510638 (-6045 475);
FORCEPROP 1 LAST TOLERANCE 5%
J 2
(-6045 425);
DISPLAY 0.510638 (-6045 425);
FORCEPROP 2 LAST CDS_LIB pure_quanta
J 0
(-6000 400);
DISPLAY INVISIBLE (-6000 400);
FORCEPROP 1 LAST PATH I3
J 2
(-6050 575);
DISPLAY 0.978723 (-6050 575);
PAINT WHITE (-6050 575);
DISPLAY INVISIBLE (-6050 575);
FORCEPROP 1 LAST PART_NUMBER CS00002JB13
J 2
(-6040 275);
DISPLAY 0.510638 (-6040 275);
DISPLAY INVISIBLE (-6040 275);
FORCEADD OFFPAGE..1
(-8225 5025);
FORCEPROP 2 LAST $XR0 151 
J 0
(-8477 5025);
DISPLAY 0.638298 (-8477 5025);
PAINT MONO (-8477 5025);
FORCEPROP 2 LAST CDS_LIB standard
J 0
(-8225 5025);
DISPLAY INVISIBLE (-8225 5025);
FORCEPROP 1 LAST OFFPAGE TRUE
J 0
(-7900 4900);
DISPLAY 0.872340 (-7900 4900);
PAINT GREEN (-7900 4900);
DISPLAY INVISIBLE (-7900 4900);
FORCEPROP 1 LAST COMMENT_BODY TRUE
J 0
(-8100 4925);
DISPLAY 0.872340 (-8100 4925);
PAINT GREEN (-8100 4925);
DISPLAY INVISIBLE (-8100 4925);
FORCEPROP 2 LAST PATH I30
J 0
(-8175 5100);
DISPLAY 0.680851 (-8175 5100);
DISPLAY INVISIBLE (-8175 5100);
FORCEADD Q_RES..1
(-6500 4875);
FORCEPROP 1 LAST LOCATION R658
J 0
(-6725 4875);
DISPLAY 0.638298 (-6725 4875);
FORCEPROP 0 LAST $SEC 1
J 0
(-6725 4925);
DISPLAY 0.680851 (-6725 4925);
PAINT MONO (-6725 4925);
DISPLAY INVISIBLE (-6725 4925);
FORCEPROP 0 LAST CDS_SEC 1
J 0
(-6725 4925);
DISPLAY 0.680851 (-6725 4925);
DISPLAY INVISIBLE (-6725 4925);
FORCEPROP 1 LASTPIN (-6600 4875) $PN 1
J 0
(-6588 4887);
DISPLAY 0.787234 (-6588 4887);
PAINT MONO (-6588 4887);
FORCEPROP 1 LASTPIN (-6400 4875) $PN 2
J 0
(-6438 4887);
DISPLAY 0.787234 (-6438 4887);
PAINT MONO (-6438 4887);
FORCEPROP 1 LAST VALUE 0
J 2
(-6275 4875);
DISPLAY 0.510638 (-6275 4875);
FORCEPROP 1 LAST TOLERANCE 5%
J 0
(-6225 4875);
DISPLAY 0.510638 (-6225 4875);
FORCEPROP 1 LAST PACK_TYPE 0402LF
J 0
(-6350 5000);
DISPLAY 0.510638 (-6350 5000);
DISPLAY INVISIBLE (-6350 5000);
FORCEPROP 1 LAST WATTAGE 1/16W
J 2
(-6375 5000);
DISPLAY 0.510638 (-6375 5000);
DISPLAY INVISIBLE (-6375 5000);
FORCEPROP 1 LAST MATERIAL CHIP
J 0
(-6625 5000);
DISPLAY 0.510638 (-6625 5000);
DISPLAY INVISIBLE (-6625 5000);
FORCEPROP 2 LAST CDS_LIB pure_quanta
J 0
(-6500 4875);
DISPLAY INVISIBLE (-6500 4875);
FORCEPROP 1 LAST PATH I31
J 0
(-6550 5025);
DISPLAY 0.978723 (-6550 5025);
PAINT WHITE (-6550 5025);
DISPLAY INVISIBLE (-6550 5025);
FORCEPROP 1 LAST PART_NUMBER CS00002JB13
J 0
(-6625 4950);
DISPLAY 0.510638 (-6625 4950);
DISPLAY INVISIBLE (-6625 4950);
FORCEADD Q_RES..1
(-6575 5425);
FORCEPROP 1 LAST LOCATION PR6818
J 0
(-6825 5425);
DISPLAY 0.638298 (-6825 5425);
FORCEPROP 0 LAST $SEC 1
J 0
(-6625 5475);
DISPLAY 0.680851 (-6625 5475);
PAINT MONO (-6625 5475);
DISPLAY INVISIBLE (-6625 5475);
FORCEPROP 0 LAST CDS_SEC 1
J 0
(-6625 5475);
DISPLAY 0.680851 (-6625 5475);
DISPLAY INVISIBLE (-6625 5475);
FORCEPROP 1 LASTPIN (-6675 5425) $PN 1
J 0
(-6663 5437);
DISPLAY 0.787234 (-6663 5437);
PAINT MONO (-6663 5437);
FORCEPROP 1 LASTPIN (-6475 5425) $PN 2
J 0
(-6513 5437);
DISPLAY 0.787234 (-6513 5437);
PAINT MONO (-6513 5437);
FORCEPROP 1 LAST MATERIAL EMPTY
J 0
(-6625 5450);
DISPLAY 0.510638 (-6625 5450);
FORCEPROP 1 LAST VALUE 1K
J 2
(-6350 5425);
DISPLAY 0.510638 (-6350 5425);
FORCEPROP 1 LAST TOLERANCE 1%
J 0
(-6300 5425);
DISPLAY 0.510638 (-6300 5425);
FORCEPROP 1 LAST WATTAGE 1/16W
J 2
(-6400 5575);
DISPLAY 0.510638 (-6400 5575);
DISPLAY INVISIBLE (-6400 5575);
FORCEPROP 1 LAST PACK_TYPE 0402LF
J 0
(-6350 5575);
DISPLAY 0.510638 (-6350 5575);
DISPLAY INVISIBLE (-6350 5575);
FORCEPROP 2 LAST CDS_LIB pure_quanta
J 0
(-6575 5425);
DISPLAY INVISIBLE (-6575 5425);
FORCEPROP 1 LAST PATH I32
J 0
(-6625 5575);
DISPLAY 0.978723 (-6625 5575);
PAINT WHITE (-6625 5575);
DISPLAY INVISIBLE (-6625 5575);
FORCEPROP 1 LAST PART_NUMBER CS21002FB06
J 0
(-6675 5525);
DISPLAY 0.510638 (-6675 5525);
DISPLAY INVISIBLE (-6675 5525);
FORCEADD Q_RES..1
(-6500 5025);
FORCEPROP 1 LAST LOCATION R657
J 0
(-6725 5025);
DISPLAY 0.638298 (-6725 5025);
FORCEPROP 0 LAST $SEC 1
J 0
(-6725 5075);
DISPLAY 0.680851 (-6725 5075);
PAINT MONO (-6725 5075);
DISPLAY INVISIBLE (-6725 5075);
FORCEPROP 0 LAST CDS_SEC 1
J 0
(-6725 5075);
DISPLAY 0.680851 (-6725 5075);
DISPLAY INVISIBLE (-6725 5075);
FORCEPROP 1 LASTPIN (-6600 5025) $PN 1
J 0
(-6588 5037);
DISPLAY 0.787234 (-6588 5037);
PAINT MONO (-6588 5037);
FORCEPROP 1 LASTPIN (-6400 5025) $PN 2
J 0
(-6438 5037);
DISPLAY 0.787234 (-6438 5037);
PAINT MONO (-6438 5037);
FORCEPROP 1 LAST MATERIAL CHIP
J 0
(-6350 4825);
DISPLAY 0.510638 (-6350 4825);
FORCEPROP 1 LAST PACK_TYPE 0402LF
J 0
(-6075 4825);
DISPLAY 0.510638 (-6075 4825);
FORCEPROP 1 LAST WATTAGE 1/16W
J 2
(-6100 4825);
DISPLAY 0.510638 (-6100 4825);
FORCEPROP 1 LAST VALUE 0
J 2
(-6275 5025);
DISPLAY 0.510638 (-6275 5025);
FORCEPROP 1 LAST TOLERANCE 5%
J 0
(-6225 5025);
DISPLAY 0.510638 (-6225 5025);
FORCEPROP 2 LAST CDS_LIB pure_quanta
J 0
(-6500 5025);
DISPLAY INVISIBLE (-6500 5025);
FORCEPROP 1 LAST PATH I33
J 0
(-6550 5175);
DISPLAY 0.978723 (-6550 5175);
PAINT WHITE (-6550 5175);
DISPLAY INVISIBLE (-6550 5175);
FORCEPROP 1 LAST PART_NUMBER CS00002JB13
J 0
(-6350 4775);
DISPLAY 0.510638 (-6350 4775);
DISPLAY INVISIBLE (-6350 4775);
FORCEADD VCC15..1
(-7075 5850);
FORCEPROP 3 LASTPIN (-7075 5800) SIG_NAME P3V3_AUX\g
J 0
(-7065 5810);
DISPLAY 0.659574 (-7065 5810);
PAINT MONO (-7065 5810);
DISPLAY INVISIBLE (-7065 5810);
FORCEPROP 1 LAST HDL_POWER P3V3_AUX
J 1
(-7075 5900);
DISPLAY 0.617021 (-7075 5900);
PAINT GREEN (-7075 5900);
FORCEPROP 2 LAST CDS_LIB pure_quanta_power
J 0
(-7075 5850);
DISPLAY INVISIBLE (-7075 5850);
FORCEPROP 1 LAST PATH I34
J 0
(-7025 5875);
DISPLAY 0.872340 (-7025 5875);
PAINT AQUA (-7025 5875);
DISPLAY INVISIBLE (-7025 5875);
FORCEADD VCC15..1
(-6650 6450);
FORCEPROP 3 LASTPIN (-6650 6400) SIG_NAME P3V3_AUX\g
J 0
(-6640 6410);
DISPLAY 0.659574 (-6640 6410);
PAINT MONO (-6640 6410);
DISPLAY INVISIBLE (-6640 6410);
FORCEPROP 1 LAST HDL_POWER P3V3_AUX
J 1
(-6650 6500);
DISPLAY 0.617021 (-6650 6500);
PAINT GREEN (-6650 6500);
FORCEPROP 2 LAST CDS_LIB pure_quanta_power
J 0
(-6650 6450);
DISPLAY INVISIBLE (-6650 6450);
FORCEPROP 1 LAST PATH I35
J 0
(-6600 6475);
DISPLAY 0.872340 (-6600 6475);
PAINT AQUA (-6600 6475);
DISPLAY INVISIBLE (-6600 6475);
FORCEADD Q_RES..1
(-6575 5575);
FORCEPROP 1 LAST LOCATION PR6804
J 0
(-6825 5575);
DISPLAY 0.638298 (-6825 5575);
FORCEPROP 0 LAST $SEC 1
J 0
(-6625 5625);
DISPLAY 0.680851 (-6625 5625);
PAINT MONO (-6625 5625);
DISPLAY INVISIBLE (-6625 5625);
FORCEPROP 0 LAST CDS_SEC 1
J 0
(-6625 5625);
DISPLAY 0.680851 (-6625 5625);
DISPLAY INVISIBLE (-6625 5625);
FORCEPROP 1 LASTPIN (-6675 5575) $PN 1
J 0
(-6663 5587);
DISPLAY 0.787234 (-6663 5587);
PAINT MONO (-6663 5587);
FORCEPROP 1 LASTPIN (-6475 5575) $PN 2
J 0
(-6513 5587);
DISPLAY 0.787234 (-6513 5587);
PAINT MONO (-6513 5587);
FORCEPROP 1 LAST VALUE 1K
J 2
(-6350 5575);
DISPLAY 0.510638 (-6350 5575);
FORCEPROP 1 LAST TOLERANCE 1%
J 0
(-6300 5575);
DISPLAY 0.510638 (-6300 5575);
FORCEPROP 1 LAST MATERIAL EMPTY
J 0
(-6625 5600);
DISPLAY 0.510638 (-6625 5600);
FORCEPROP 1 LAST WATTAGE 1/16W
J 2
(-6400 5725);
DISPLAY 0.510638 (-6400 5725);
DISPLAY INVISIBLE (-6400 5725);
FORCEPROP 1 LAST PACK_TYPE 0402LF
J 0
(-6350 5725);
DISPLAY 0.510638 (-6350 5725);
DISPLAY INVISIBLE (-6350 5725);
FORCEPROP 2 LAST CDS_LIB pure_quanta
J 0
(-6575 5575);
DISPLAY INVISIBLE (-6575 5575);
FORCEPROP 1 LAST PATH I36
J 0
(-6625 5725);
DISPLAY 0.978723 (-6625 5725);
PAINT WHITE (-6625 5725);
DISPLAY INVISIBLE (-6625 5725);
FORCEPROP 1 LAST PART_NUMBER CS21002FB06
J 0
(-6675 5675);
DISPLAY 0.510638 (-6675 5675);
DISPLAY INVISIBLE (-6675 5675);
FORCEADD Q_RES..1
(-6575 5725);
FORCEPROP 1 LAST LOCATION PR6806
J 0
(-6825 5725);
DISPLAY 0.638298 (-6825 5725);
FORCEPROP 0 LAST $SEC 1
J 0
(-6350 5900);
DISPLAY 0.680851 (-6350 5900);
PAINT MONO (-6350 5900);
DISPLAY INVISIBLE (-6350 5900);
FORCEPROP 0 LAST CDS_SEC 1
J 0
(-6350 5900);
DISPLAY 0.680851 (-6350 5900);
DISPLAY INVISIBLE (-6350 5900);
FORCEPROP 1 LASTPIN (-6675 5725) $PN 1
J 0
(-6663 5737);
DISPLAY 0.787234 (-6663 5737);
PAINT MONO (-6663 5737);
FORCEPROP 1 LASTPIN (-6475 5725) $PN 2
J 0
(-6513 5737);
DISPLAY 0.787234 (-6513 5737);
PAINT MONO (-6513 5737);
FORCEPROP 1 LAST MATERIAL EMPTY
J 0
(-6675 5875);
DISPLAY 0.510638 (-6675 5875);
FORCEPROP 1 LAST WATTAGE 1/16W
J 2
(-6400 5875);
DISPLAY 0.510638 (-6400 5875);
FORCEPROP 1 LAST PACK_TYPE 0402LF
J 0
(-6350 5875);
DISPLAY 0.510638 (-6350 5875);
FORCEPROP 1 LAST TOLERANCE 1%
J 0
(-6300 5725);
DISPLAY 0.510638 (-6300 5725);
FORCEPROP 1 LAST VALUE 1K
J 2
(-6350 5725);
DISPLAY 0.510638 (-6350 5725);
FORCEPROP 2 LAST CDS_LIB pure_quanta
J 0
(-6575 5725);
DISPLAY INVISIBLE (-6575 5725);
FORCEPROP 1 LAST PATH I37
J 0
(-6625 5875);
DISPLAY 0.978723 (-6625 5875);
PAINT WHITE (-6625 5875);
DISPLAY INVISIBLE (-6625 5875);
FORCEPROP 1 LAST PART_NUMBER CS21002FB06
J 0
(-6675 5825);
DISPLAY 0.510638 (-6675 5825);
DISPLAY INVISIBLE (-6675 5825);
FORCEADD Q_RES..1
(-6500 6025);
FORCEPROP 1 LAST LOCATION R662
J 0
(-6775 6025);
DISPLAY 0.638298 (-6775 6025);
FORCEPROP 0 LAST $SEC 1
J 0
(-6775 6075);
DISPLAY 0.680851 (-6775 6075);
PAINT MONO (-6775 6075);
DISPLAY INVISIBLE (-6775 6075);
FORCEPROP 0 LAST CDS_SEC 1
J 0
(-6775 6075);
DISPLAY 0.680851 (-6775 6075);
DISPLAY INVISIBLE (-6775 6075);
FORCEPROP 1 LASTPIN (-6600 6025) $PN 1
J 0
(-6588 6037);
DISPLAY 0.787234 (-6588 6037);
PAINT MONO (-6588 6037);
FORCEPROP 1 LASTPIN (-6400 6025) $PN 2
J 0
(-6438 6037);
DISPLAY 0.787234 (-6438 6037);
PAINT MONO (-6438 6037);
FORCEPROP 1 LAST TOLERANCE 5%
J 0
(-6225 6025);
DISPLAY 0.510638 (-6225 6025);
FORCEPROP 1 LAST VALUE 0
J 2
(-6275 6025);
DISPLAY 0.510638 (-6275 6025);
FORCEPROP 1 LAST WATTAGE 1/16W
J 2
(-6375 6150);
DISPLAY 0.510638 (-6375 6150);
DISPLAY INVISIBLE (-6375 6150);
FORCEPROP 1 LAST MATERIAL CHIP
J 0
(-6625 6150);
DISPLAY 0.510638 (-6625 6150);
DISPLAY INVISIBLE (-6625 6150);
FORCEPROP 1 LAST PACK_TYPE 0402LF
J 0
(-6350 6150);
DISPLAY 0.510638 (-6350 6150);
DISPLAY INVISIBLE (-6350 6150);
FORCEPROP 2 LAST CDS_LIB pure_quanta
J 0
(-6500 6025);
DISPLAY INVISIBLE (-6500 6025);
FORCEPROP 1 LAST PATH I38
J 0
(-6550 6175);
DISPLAY 0.978723 (-6550 6175);
PAINT WHITE (-6550 6175);
DISPLAY INVISIBLE (-6550 6175);
FORCEPROP 1 LAST PART_NUMBER CS00002JB13
J 0
(-6625 6100);
DISPLAY 0.510638 (-6625 6100);
DISPLAY INVISIBLE (-6625 6100);
FORCEADD Q_RES..1
(-7225 6175);
FORCEPROP 1 LAST LOCATION R661
J 0
(-7500 6175);
DISPLAY 0.638298 (-7500 6175);
FORCEPROP 0 LAST $SEC 1
J 0
(-7075 6300);
DISPLAY 0.680851 (-7075 6300);
PAINT MONO (-7075 6300);
DISPLAY INVISIBLE (-7075 6300);
FORCEPROP 0 LAST CDS_SEC 1
J 0
(-7075 6300);
DISPLAY 0.680851 (-7075 6300);
DISPLAY INVISIBLE (-7075 6300);
FORCEPROP 1 LASTPIN (-7325 6175) $PN 1
J 0
(-7313 6187);
DISPLAY 0.787234 (-7313 6187);
PAINT MONO (-7313 6187);
FORCEPROP 1 LASTPIN (-7125 6175) $PN 2
J 0
(-7163 6187);
DISPLAY 0.787234 (-7163 6187);
PAINT MONO (-7163 6187);
FORCEPROP 1 LAST PACK_TYPE 0402LF
J 0
(-7075 6275);
DISPLAY 0.510638 (-7075 6275);
FORCEPROP 1 LAST WATTAGE 1/16W
J 2
(-7100 6275);
DISPLAY 0.510638 (-7100 6275);
FORCEPROP 1 LAST MATERIAL CHIP
J 0
(-7350 6275);
DISPLAY 0.510638 (-7350 6275);
FORCEPROP 1 LAST VALUE 0
J 2
(-7000 6175);
DISPLAY 0.510638 (-7000 6175);
FORCEPROP 1 LAST TOLERANCE 5%
J 0
(-6950 6175);
DISPLAY 0.510638 (-6950 6175);
FORCEPROP 2 LAST CDS_LIB pure_quanta
J 0
(-7225 6175);
DISPLAY INVISIBLE (-7225 6175);
FORCEPROP 1 LAST PATH I39
J 0
(-7275 6325);
DISPLAY 0.978723 (-7275 6325);
PAINT WHITE (-7275 6325);
DISPLAY INVISIBLE (-7275 6325);
FORCEPROP 1 LAST PART_NUMBER CS00002JB13
J 0
(-7350 6225);
DISPLAY 0.510638 (-7350 6225);
DISPLAY INVISIBLE (-7350 6225);
FORCEADD UNIVERSAL_GND..1
(-5875 100);
FORCEPROP 3 LASTPIN (-5875 150) SIG_NAME GND\g
J 0
(-5865 160);
DISPLAY 0.659574 (-5865 160);
PAINT MONO (-5865 160);
DISPLAY INVISIBLE (-5865 160);
FORCEPROP 2 LAST CDS_LIB pure_quanta_power
J 0
(-5875 100);
DISPLAY INVISIBLE (-5875 100);
FORCEPROP 1 LAST HDL_POWER GND
J 1
(-5850 25);
DISPLAY 0.872340 (-5850 25);
PAINT GREEN (-5850 25);
DISPLAY INVISIBLE (-5850 25);
FORCEPROP 1 LAST PATH I4
J 0
(-5800 100);
DISPLAY 0.872340 (-5800 100);
PAINT AQUA (-5800 100);
DISPLAY INVISIBLE (-5800 100);
FORCEADD UNIVERSAL_GND..1
R 5
(-6350 5100);
FORCEPROP 3 LASTPIN (-6300 5100) SIG_NAME GND\g
J 0
(-6290 5110);
DISPLAY 0.659574 (-6290 5110);
PAINT MONO (-6290 5110);
DISPLAY INVISIBLE (-6290 5110);
FORCEPROP 2 LAST CDS_LIB pure_quanta_power
J 0
(-6350 5100);
DISPLAY INVISIBLE (-6350 5100);
FORCEPROP 1 LAST HDL_POWER GND
R 3
J 1
(-6425 5075);
DISPLAY 0.872340 (-6425 5075);
PAINT GREEN (-6425 5075);
DISPLAY INVISIBLE (-6425 5075);
FORCEPROP 1 LAST PATH I41
R 3
J 0
(-6350 5025);
DISPLAY 0.872340 (-6350 5025);
PAINT AQUA (-6350 5025);
DISPLAY INVISIBLE (-6350 5025);
FORCEADD Q_RES..2
(-6200 5250);
FORCEPROP 1 LAST LOCATION PR6811
J 0
(-6155 5375);
DISPLAY 0.638298 (-6155 5375);
FORCEPROP 0 LAST $SEC 1
J 0
(-6150 5425);
DISPLAY 0.680851 (-6150 5425);
PAINT MONO (-6150 5425);
DISPLAY INVISIBLE (-6150 5425);
FORCEPROP 0 LAST CDS_SEC 1
J 0
(-6150 5425);
DISPLAY 0.680851 (-6150 5425);
DISPLAY INVISIBLE (-6150 5425);
FORCEPROP 1 LASTPIN (-6200 5350) $PN 1
J 0
(-6195 5312);
DISPLAY 0.787234 (-6195 5312);
PAINT MONO (-6195 5312);
FORCEPROP 1 LASTPIN (-6200 5150) $PN 2
J 0
(-6195 5160);
DISPLAY 0.787234 (-6195 5160);
PAINT MONO (-6195 5160);
FORCEPROP 1 LAST MATERIAL CHIP
J 0
(-6160 5175);
DISPLAY 0.510638 (-6160 5175);
FORCEPROP 1 LAST PACK_TYPE 0402LF
J 0
(-6160 5075);
DISPLAY 0.510638 (-6160 5075);
FORCEPROP 1 LAST VALUE 0
J 0
(-6155 5325);
DISPLAY 0.510638 (-6155 5325);
FORCEPROP 1 LAST TOLERANCE 5%
J 0
(-6155 5275);
DISPLAY 0.510638 (-6155 5275);
FORCEPROP 1 LAST WATTAGE 1/16W
J 0
(-6160 5225);
DISPLAY 0.510638 (-6160 5225);
FORCEPROP 2 LAST CDS_LIB pure_quanta
J 0
(-6200 5250);
DISPLAY INVISIBLE (-6200 5250);
FORCEPROP 1 LAST PATH I42
J 0
(-6150 5425);
DISPLAY 0.978723 (-6150 5425);
PAINT WHITE (-6150 5425);
DISPLAY INVISIBLE (-6150 5425);
FORCEPROP 1 LAST PART_NUMBER CS00002JB13
J 0
(-6160 5125);
DISPLAY 0.510638 (-6160 5125);
DISPLAY INVISIBLE (-6160 5125);
FORCEADD Q_RES..2
(-5850 5250);
FORCEPROP 1 LAST LOCATION PR6820
J 0
(-5805 5375);
DISPLAY 0.638298 (-5805 5375);
FORCEPROP 0 LAST $SEC 1
J 0
(-5800 5425);
DISPLAY 0.680851 (-5800 5425);
PAINT MONO (-5800 5425);
DISPLAY INVISIBLE (-5800 5425);
FORCEPROP 0 LAST CDS_SEC 1
J 0
(-5800 5425);
DISPLAY 0.680851 (-5800 5425);
DISPLAY INVISIBLE (-5800 5425);
FORCEPROP 1 LASTPIN (-5850 5350) $PN 1
J 0
(-5845 5312);
DISPLAY 0.787234 (-5845 5312);
PAINT MONO (-5845 5312);
FORCEPROP 1 LASTPIN (-5850 5150) $PN 2
J 0
(-5845 5160);
DISPLAY 0.787234 (-5845 5160);
PAINT MONO (-5845 5160);
FORCEPROP 1 LAST WATTAGE 1/16W
J 0
(-5810 5225);
DISPLAY 0.510638 (-5810 5225);
FORCEPROP 1 LAST TOLERANCE 5%
J 0
(-5805 5275);
DISPLAY 0.510638 (-5805 5275);
FORCEPROP 1 LAST PACK_TYPE 0402LF
J 0
(-5810 5075);
DISPLAY 0.510638 (-5810 5075);
FORCEPROP 1 LAST VALUE 0
J 0
(-5805 5325);
DISPLAY 0.510638 (-5805 5325);
FORCEPROP 1 LAST MATERIAL CHIP
J 0
(-5810 5175);
DISPLAY 0.510638 (-5810 5175);
FORCEPROP 2 LAST CDS_LIB pure_quanta
J 0
(-5850 5250);
DISPLAY INVISIBLE (-5850 5250);
FORCEPROP 1 LAST PATH I43
J 0
(-5800 5425);
DISPLAY 0.978723 (-5800 5425);
PAINT WHITE (-5800 5425);
DISPLAY INVISIBLE (-5800 5425);
FORCEPROP 1 LAST PART_NUMBER CS00002JB13
J 0
(-5810 5125);
DISPLAY 0.510638 (-5810 5125);
DISPLAY INVISIBLE (-5810 5125);
FORCEADD Q_RES..2
(-5500 5250);
FORCEPROP 1 LAST LOCATION PR6802
J 0
(-5455 5375);
DISPLAY 0.638298 (-5455 5375);
FORCEPROP 0 LAST $SEC 1
J 0
(-5450 5425);
DISPLAY 0.680851 (-5450 5425);
PAINT MONO (-5450 5425);
DISPLAY INVISIBLE (-5450 5425);
FORCEPROP 0 LAST CDS_SEC 1
J 0
(-5450 5425);
DISPLAY 0.680851 (-5450 5425);
DISPLAY INVISIBLE (-5450 5425);
FORCEPROP 1 LASTPIN (-5500 5350) $PN 1
J 0
(-5495 5312);
DISPLAY 0.787234 (-5495 5312);
PAINT MONO (-5495 5312);
FORCEPROP 1 LASTPIN (-5500 5150) $PN 2
J 0
(-5495 5160);
DISPLAY 0.787234 (-5495 5160);
PAINT MONO (-5495 5160);
FORCEPROP 1 LAST VALUE 0
J 0
(-5455 5325);
DISPLAY 0.510638 (-5455 5325);
FORCEPROP 1 LAST TOLERANCE 5%
J 0
(-5455 5275);
DISPLAY 0.510638 (-5455 5275);
FORCEPROP 1 LAST MATERIAL EMPTY
J 0
(-5460 5175);
DISPLAY 0.510638 (-5460 5175);
FORCEPROP 1 LAST PACK_TYPE 0402LF
J 0
(-5460 5075);
DISPLAY 0.510638 (-5460 5075);
FORCEPROP 1 LAST WATTAGE 1/16W
J 0
(-5460 5225);
DISPLAY 0.510638 (-5460 5225);
FORCEPROP 2 LAST CDS_LIB pure_quanta
J 0
(-5500 5250);
DISPLAY INVISIBLE (-5500 5250);
FORCEPROP 1 LAST PATH I44
J 0
(-5450 5425);
DISPLAY 0.978723 (-5450 5425);
PAINT WHITE (-5450 5425);
DISPLAY INVISIBLE (-5450 5425);
FORCEPROP 1 LAST PART_NUMBER CS00002JB13
J 0
(-5460 5125);
DISPLAY 0.510638 (-5460 5125);
DISPLAY INVISIBLE (-5460 5125);
FORCEADD Q_CAP..2
(-5650 6325);
FORCEPROP 1 LAST LOCATION C107
J 1
(-5825 6325);
DISPLAY 0.638298 (-5825 6325);
FORCEPROP 0 LAST $SEC 1
J 0
(-5450 6500);
DISPLAY 0.680851 (-5450 6500);
PAINT MONO (-5450 6500);
DISPLAY INVISIBLE (-5450 6500);
FORCEPROP 0 LAST CDS_SEC 1
J 0
(-5450 6500);
DISPLAY 0.680851 (-5450 6500);
DISPLAY INVISIBLE (-5450 6500);
FORCEPROP 1 LASTPIN (-5750 6325) $PN 1
J 0
(-5760 6340);
DISPLAY 0.787234 (-5760 6340);
PAINT MONO (-5760 6340);
FORCEPROP 1 LASTPIN (-5550 6325) $PN 2
J 0
(-5565 6340);
DISPLAY 0.787234 (-5565 6340);
PAINT MONO (-5565 6340);
FORCEPROP 1 LAST MATERIAL EMPTY
J 0
(-5775 6475);
DISPLAY 0.510638 (-5775 6475);
FORCEPROP 1 LAST VALUE 1000PF
J 2
(-5325 6325);
DISPLAY 0.510638 (-5325 6325);
FORCEPROP 1 LAST VOLTAGE 50V
J 0
(-5625 6475);
DISPLAY 0.510638 (-5625 6475);
FORCEPROP 1 LAST TOLERANCE 5%
J 2
(-5250 6325);
DISPLAY 0.510638 (-5250 6325);
FORCEPROP 1 LAST PACK_TYPE 0402
J 1
(-5450 6475);
DISPLAY 0.510638 (-5450 6475);
FORCEPROP 2 LAST CDS_LIB pure_quanta
J 0
(-5650 6325);
DISPLAY INVISIBLE (-5650 6325);
FORCEPROP 1 LAST PATH I45
J 0
(-5650 6525);
DISPLAY 0.978723 (-5650 6525);
PAINT WHITE (-5650 6525);
DISPLAY INVISIBLE (-5650 6525);
FORCEPROP 1 LAST PART_NUMBER TMP_QCH21006JB10
J 1
(-5600 6425);
DISPLAY 0.510638 (-5600 6425);
DISPLAY INVISIBLE (-5600 6425);
FORCEADD Q_RES..2
R 2
(-5250 400);
FORCEPROP 1 LAST LOCATION PR6813
J 2
(-5295 525);
DISPLAY 0.808511 (-5295 525);
FORCEPROP 0 LAST $SEC 1
J 0
(-5275 575);
DISPLAY 0.680851 (-5275 575);
PAINT MONO (-5275 575);
DISPLAY INVISIBLE (-5275 575);
FORCEPROP 0 LAST CDS_SEC 1
J 0
(-5275 575);
DISPLAY 0.680851 (-5275 575);
DISPLAY INVISIBLE (-5275 575);
FORCEPROP 1 LASTPIN (-5250 500) $PN 1
J 2
(-5255 462);
DISPLAY 0.787234 (-5255 462);
PAINT MONO (-5255 462);
FORCEPROP 1 LASTPIN (-5250 300) $PN 2
J 2
(-5255 310);
DISPLAY 0.787234 (-5255 310);
PAINT MONO (-5255 310);
FORCEPROP 1 LAST WATTAGE 1/16W
J 2
(-5290 375);
DISPLAY 0.510638 (-5290 375);
FORCEPROP 1 LAST VALUE 1K
J 2
(-5295 475);
DISPLAY 0.510638 (-5295 475);
FORCEPROP 1 LAST TOLERANCE 1%
J 2
(-5295 425);
DISPLAY 0.510638 (-5295 425);
FORCEPROP 1 LAST MATERIAL EMPTY
J 2
(-5290 325);
DISPLAY 0.510638 (-5290 325);
FORCEPROP 1 LAST PACK_TYPE 0402LF
J 2
(-5290 225);
DISPLAY 0.510638 (-5290 225);
FORCEPROP 2 LAST CDS_LIB pure_quanta
J 0
(-5250 400);
DISPLAY INVISIBLE (-5250 400);
FORCEPROP 1 LAST PATH I46
J 2
(-5300 575);
DISPLAY 0.978723 (-5300 575);
PAINT WHITE (-5300 575);
DISPLAY INVISIBLE (-5300 575);
FORCEPROP 1 LAST PART_NUMBER CS21002FB06
J 2
(-5290 275);
DISPLAY 0.510638 (-5290 275);
DISPLAY INVISIBLE (-5290 275);
FORCEADD UNIVERSAL_GND..1
(-5125 100);
FORCEPROP 3 LASTPIN (-5125 150) SIG_NAME GND\g
J 0
(-5115 160);
DISPLAY 0.659574 (-5115 160);
PAINT MONO (-5115 160);
DISPLAY INVISIBLE (-5115 160);
FORCEPROP 2 LAST CDS_LIB pure_quanta_power
J 0
(-5125 100);
DISPLAY INVISIBLE (-5125 100);
FORCEPROP 1 LAST HDL_POWER GND
J 1
(-5100 25);
DISPLAY 0.872340 (-5100 25);
PAINT GREEN (-5100 25);
DISPLAY INVISIBLE (-5100 25);
FORCEPROP 1 LAST PATH I47
J 0
(-5050 100);
DISPLAY 0.872340 (-5050 100);
PAINT AQUA (-5050 100);
DISPLAY INVISIBLE (-5050 100);
FORCEADD Q_CAP..1
(-5125 400);
FORCEPROP 1 LAST LOCATION PC819
J 0
(-5075 500);
DISPLAY 0.787234 (-5075 500);
FORCEPROP 0 LAST $SEC 1
J 0
(-5075 550);
DISPLAY 0.680851 (-5075 550);
PAINT MONO (-5075 550);
DISPLAY INVISIBLE (-5075 550);
FORCEPROP 0 LAST CDS_SEC 1
J 0
(-5075 550);
DISPLAY 0.680851 (-5075 550);
DISPLAY INVISIBLE (-5075 550);
FORCEPROP 1 LASTPIN (-5125 500) $PN 1
J 0
(-5115 480);
DISPLAY 0.787234 (-5115 480);
PAINT MONO (-5115 480);
FORCEPROP 1 LASTPIN (-5125 300) $PN 2
J 0
(-5115 280);
DISPLAY 0.787234 (-5115 280);
PAINT MONO (-5115 280);
FORCEPROP 1 LAST MATERIAL X7R
J 0
(-5075 300);
DISPLAY 0.510638 (-5075 300);
FORCEPROP 1 LAST PACK_TYPE 0402
J 0
(-5075 200);
DISPLAY 0.510638 (-5075 200);
FORCEPROP 1 LAST TOLERANCE 10%
J 0
(-5075 350);
DISPLAY 0.510638 (-5075 350);
FORCEPROP 1 LAST VOLTAGE 25V
J 0
(-5075 400);
DISPLAY 0.510638 (-5075 400);
FORCEPROP 1 LAST VALUE 0.1UF
J 0
(-5075 450);
DISPLAY 0.510638 (-5075 450);
FORCEPROP 2 LAST CDS_LIB pure_quanta
J 0
(-5125 400);
DISPLAY INVISIBLE (-5125 400);
FORCEPROP 1 LAST PATH I48
J 0
(-5075 550);
DISPLAY 0.978723 (-5075 550);
PAINT WHITE (-5075 550);
DISPLAY INVISIBLE (-5075 550);
FORCEPROP 1 LAST PART_NUMBER CH4104K1B00
J 0
(-5075 250);
DISPLAY 0.510638 (-5075 250);
DISPLAY INVISIBLE (-5075 250);
FORCEADD UNIVERSAL_GND..1
(-4900 500);
FORCEPROP 3 LASTPIN (-4900 550) SIG_NAME GND\g
J 0
(-4890 560);
DISPLAY 0.659574 (-4890 560);
PAINT MONO (-4890 560);
DISPLAY INVISIBLE (-4890 560);
FORCEPROP 2 LAST CDS_LIB pure_quanta_power
J 0
(-4900 500);
DISPLAY INVISIBLE (-4900 500);
FORCEPROP 1 LAST HDL_POWER GND
J 1
(-4875 425);
DISPLAY 0.872340 (-4875 425);
PAINT GREEN (-4875 425);
DISPLAY INVISIBLE (-4875 425);
FORCEPROP 1 LAST PATH I49
J 0
(-4825 500);
DISPLAY 0.872340 (-4825 500);
PAINT AQUA (-4825 500);
DISPLAY INVISIBLE (-4825 500);
FORCEADD Q_CAP..1
(-5875 400);
FORCEPROP 1 LAST LOCATION PC514
J 0
(-5825 500);
DISPLAY 0.808511 (-5825 500);
FORCEPROP 0 LAST $SEC 1
J 0
(-5825 550);
DISPLAY 0.680851 (-5825 550);
PAINT MONO (-5825 550);
DISPLAY INVISIBLE (-5825 550);
FORCEPROP 0 LAST CDS_SEC 1
J 0
(-5825 550);
DISPLAY 0.680851 (-5825 550);
DISPLAY INVISIBLE (-5825 550);
FORCEPROP 1 LASTPIN (-5875 500) $PN 1
J 0
(-5865 480);
DISPLAY 0.787234 (-5865 480);
PAINT MONO (-5865 480);
FORCEPROP 1 LASTPIN (-5875 300) $PN 2
J 0
(-5865 280);
DISPLAY 0.787234 (-5865 280);
PAINT MONO (-5865 280);
FORCEPROP 1 LAST TOLERANCE 10%
J 0
(-5825 350);
DISPLAY 0.510638 (-5825 350);
FORCEPROP 1 LAST VALUE 0.1UF
J 0
(-5825 450);
DISPLAY 0.510638 (-5825 450);
FORCEPROP 1 LAST VOLTAGE 25V
J 0
(-5825 400);
DISPLAY 0.510638 (-5825 400);
FORCEPROP 1 LAST PACK_TYPE 0402
J 0
(-5825 200);
DISPLAY 0.510638 (-5825 200);
FORCEPROP 1 LAST MATERIAL EMPTY
J 0
(-5825 300);
DISPLAY 0.510638 (-5825 300);
FORCEPROP 2 LAST CDS_LIB pure_quanta
J 0
(-5875 400);
DISPLAY INVISIBLE (-5875 400);
FORCEPROP 1 LAST PATH I5
J 0
(-5825 550);
DISPLAY 0.978723 (-5825 550);
PAINT WHITE (-5825 550);
DISPLAY INVISIBLE (-5825 550);
FORCEPROP 1 LAST PART_NUMBER CH4104K1B00
J 0
(-5825 250);
DISPLAY 0.510638 (-5825 250);
DISPLAY INVISIBLE (-5825 250);
FORCEADD UNIVERSAL_GND..1
(-2500 550);
FORCEPROP 3 LASTPIN (-2500 600) SIG_NAME GND\g
J 0
(-2490 610);
DISPLAY 0.659574 (-2490 610);
PAINT MONO (-2490 610);
DISPLAY INVISIBLE (-2490 610);
FORCEPROP 2 LAST CDS_LIB pure_quanta_power
J 0
(-2500 550);
DISPLAY INVISIBLE (-2500 550);
FORCEPROP 1 LAST HDL_POWER GND
J 1
(-2475 475);
DISPLAY 0.872340 (-2475 475);
PAINT GREEN (-2475 475);
DISPLAY INVISIBLE (-2475 475);
FORCEPROP 1 LAST PATH I50
J 0
(-2425 550);
DISPLAY 0.872340 (-2425 550);
PAINT AQUA (-2425 550);
DISPLAY INVISIBLE (-2425 550);
FORCEADD Q_CAP..1
(-2500 775);
FORCEPROP 1 LAST LOCATION PC523
J 0
(-2450 875);
DISPLAY 0.808511 (-2450 875);
FORCEPROP 0 LAST $SEC 1
J 0
(-2450 925);
DISPLAY 0.680851 (-2450 925);
PAINT MONO (-2450 925);
DISPLAY INVISIBLE (-2450 925);
FORCEPROP 0 LAST CDS_SEC 1
J 0
(-2450 925);
DISPLAY 0.680851 (-2450 925);
DISPLAY INVISIBLE (-2450 925);
FORCEPROP 1 LASTPIN (-2500 875) $PN 1
J 0
(-2490 855);
DISPLAY 0.787234 (-2490 855);
PAINT MONO (-2490 855);
FORCEPROP 1 LASTPIN (-2500 675) $PN 2
J 0
(-2490 655);
DISPLAY 0.787234 (-2490 655);
PAINT MONO (-2490 655);
FORCEPROP 1 LAST TOLERANCE 10%
J 0
(-2450 725);
DISPLAY 0.510638 (-2450 725);
FORCEPROP 1 LAST PACK_TYPE 0402
J 0
(-2450 575);
DISPLAY 0.510638 (-2450 575);
FORCEPROP 1 LAST VALUE 470PF
J 0
(-2450 825);
DISPLAY 0.510638 (-2450 825);
FORCEPROP 1 LAST VOLTAGE 50V
J 0
(-2450 775);
DISPLAY 0.510638 (-2450 775);
FORCEPROP 1 LAST MATERIAL X7R
J 0
(-2450 675);
DISPLAY 0.510638 (-2450 675);
FORCEPROP 2 LAST CDS_LIB pure_quanta
J 0
(-2500 775);
DISPLAY INVISIBLE (-2500 775);
FORCEPROP 1 LAST PATH I51
J 0
(-2450 925);
DISPLAY 0.978723 (-2450 925);
PAINT WHITE (-2450 925);
DISPLAY INVISIBLE (-2450 925);
FORCEPROP 1 LAST PART_NUMBER TMP_QCH14706KB18
J 0
(-2450 625);
DISPLAY 0.510638 (-2450 625);
DISPLAY INVISIBLE (-2450 625);
FORCEADD Q_RES..1
(-2125 1275);
FORCEPROP 1 LAST LOCATION PR6548
J 0
(-2175 1325);
DISPLAY 0.978723 (-2175 1325);
FORCEPROP 0 LAST $SEC 1
J 0
(-2175 1375);
DISPLAY 0.680851 (-2175 1375);
PAINT MONO (-2175 1375);
DISPLAY INVISIBLE (-2175 1375);
FORCEPROP 0 LAST CDS_SEC 1
J 0
(-2175 1375);
DISPLAY 0.680851 (-2175 1375);
DISPLAY INVISIBLE (-2175 1375);
FORCEPROP 1 LASTPIN (-2225 1275) $PN 1
J 0
(-2213 1287);
DISPLAY 0.787234 (-2213 1287);
PAINT MONO (-2213 1287);
FORCEPROP 1 LASTPIN (-2025 1275) $PN 2
J 0
(-2063 1287);
DISPLAY 0.787234 (-2063 1287);
PAINT MONO (-2063 1287);
FORCEPROP 1 LAST WATTAGE 1/16W
J 2
(-2250 1200);
DISPLAY 0.510638 (-2250 1200);
FORCEPROP 1 LAST MATERIAL CHIP
J 0
(-2500 1200);
DISPLAY 0.510638 (-2500 1200);
FORCEPROP 1 LAST TOLERANCE 5%
J 0
(-1925 1300);
DISPLAY 0.510638 (-1925 1300);
FORCEPROP 1 LAST VALUE 0
J 2
(-1975 1300);
DISPLAY 0.510638 (-1975 1300);
FORCEPROP 1 LAST PACK_TYPE 0402LF
J 0
(-1975 1400);
DISPLAY 0.510638 (-1975 1400);
DISPLAY INVISIBLE (-1975 1400);
FORCEPROP 2 LAST CDS_LIB pure_quanta
J 0
(-2125 1275);
DISPLAY INVISIBLE (-2125 1275);
FORCEPROP 1 LAST PATH I52
J 0
(-2175 1425);
DISPLAY 0.978723 (-2175 1425);
PAINT WHITE (-2175 1425);
DISPLAY INVISIBLE (-2175 1425);
FORCEPROP 1 LAST PART_NUMBER CS00002JB13
J 0
(-2225 1200);
DISPLAY 0.510638 (-2225 1200);
DISPLAY INVISIBLE (-2225 1200);
FORCEADD UNIVERSAL_GND..1
(-1800 525);
FORCEPROP 3 LASTPIN (-1800 575) SIG_NAME GND\g
J 0
(-1790 585);
DISPLAY 0.659574 (-1790 585);
PAINT MONO (-1790 585);
DISPLAY INVISIBLE (-1790 585);
FORCEPROP 2 LAST CDS_LIB pure_quanta_power
J 0
(-1800 525);
DISPLAY INVISIBLE (-1800 525);
FORCEPROP 1 LAST HDL_POWER GND
J 1
(-1775 450);
DISPLAY 0.872340 (-1775 450);
PAINT GREEN (-1775 450);
DISPLAY INVISIBLE (-1775 450);
FORCEPROP 1 LAST PATH I53
J 0
(-1725 525);
DISPLAY 0.872340 (-1725 525);
PAINT AQUA (-1725 525);
DISPLAY INVISIBLE (-1725 525);
FORCEADD Q_RES..2
(-1800 775);
FORCEPROP 1 LAST LOCATION PR6815
J 0
(-1755 900);
DISPLAY 0.787234 (-1755 900);
FORCEPROP 0 LAST $SEC 1
J 0
(-1750 950);
DISPLAY 0.680851 (-1750 950);
PAINT MONO (-1750 950);
DISPLAY INVISIBLE (-1750 950);
FORCEPROP 0 LAST CDS_SEC 1
J 0
(-1750 950);
DISPLAY 0.680851 (-1750 950);
DISPLAY INVISIBLE (-1750 950);
FORCEPROP 1 LASTPIN (-1800 875) $PN 1
J 0
(-1795 837);
DISPLAY 0.787234 (-1795 837);
PAINT MONO (-1795 837);
FORCEPROP 1 LASTPIN (-1800 675) $PN 2
J 0
(-1795 685);
DISPLAY 0.787234 (-1795 685);
PAINT MONO (-1795 685);
FORCEPROP 1 LAST VALUE 10K
J 0
(-1755 850);
DISPLAY 0.510638 (-1755 850);
FORCEPROP 1 LAST PACK_TYPE 0402LF
J 0
(-1760 600);
DISPLAY 0.510638 (-1760 600);
FORCEPROP 1 LAST TOLERANCE 1%
J 0
(-1755 800);
DISPLAY 0.510638 (-1755 800);
FORCEPROP 1 LAST MATERIAL EMPTY
J 0
(-1760 700);
DISPLAY 0.510638 (-1760 700);
FORCEPROP 1 LAST WATTAGE 1/16W
J 0
(-1760 750);
DISPLAY 0.510638 (-1760 750);
FORCEPROP 2 LAST CDS_LIB pure_quanta
J 0
(-1800 775);
DISPLAY INVISIBLE (-1800 775);
FORCEPROP 1 LAST PATH I54
J 0
(-1750 950);
DISPLAY 0.978723 (-1750 950);
PAINT WHITE (-1750 950);
DISPLAY INVISIBLE (-1750 950);
FORCEPROP 1 LAST PART_NUMBER CS31002FB08
J 0
(-1760 650);
DISPLAY 0.510638 (-1760 650);
DISPLAY INVISIBLE (-1760 650);
FORCEADD UNIVERSAL_GND..1
(-1750 1150);
FORCEPROP 3 LASTPIN (-1750 1200) SIG_NAME GND\g
J 0
(-1740 1210);
DISPLAY 0.659574 (-1740 1210);
PAINT MONO (-1740 1210);
DISPLAY INVISIBLE (-1740 1210);
FORCEPROP 2 LAST CDS_LIB pure_quanta_power
J 0
(-1750 1150);
DISPLAY INVISIBLE (-1750 1150);
FORCEPROP 1 LAST HDL_POWER GND
J 1
(-1725 1075);
DISPLAY 0.872340 (-1725 1075);
PAINT GREEN (-1725 1075);
DISPLAY INVISIBLE (-1725 1075);
FORCEPROP 1 LAST PATH I55
J 0
(-1675 1150);
DISPLAY 0.872340 (-1675 1150);
PAINT AQUA (-1675 1150);
DISPLAY INVISIBLE (-1675 1150);
FORCEADD Q_RES..1
(-1975 1675);
FORCEPROP 1 LAST LOCATION PR6816
J 0
(-2250 1675);
DISPLAY 0.787234 (-2250 1675);
FORCEPROP 0 LAST $SEC 1
J 0
(-1675 1725);
DISPLAY 0.680851 (-1675 1725);
PAINT MONO (-1675 1725);
DISPLAY INVISIBLE (-1675 1725);
FORCEPROP 0 LAST CDS_SEC 1
J 0
(-1675 1725);
DISPLAY 0.680851 (-1675 1725);
DISPLAY INVISIBLE (-1675 1725);
FORCEPROP 1 LASTPIN (-2075 1675) $PN 1
J 0
(-2063 1687);
DISPLAY 0.787234 (-2063 1687);
PAINT MONO (-2063 1687);
FORCEPROP 1 LASTPIN (-1875 1675) $PN 2
J 0
(-1913 1687);
DISPLAY 0.787234 (-1913 1687);
PAINT MONO (-1913 1687);
FORCEPROP 1 LAST MATERIAL CHIP
J 0
(-2175 1625);
DISPLAY 0.638298 (-2175 1625);
FORCEPROP 1 LAST PACK_TYPE 0402LF
J 0
(-2025 1625);
DISPLAY 0.638298 (-2025 1625);
FORCEPROP 1 LAST VALUE 0
J 2
(-1800 1675);
DISPLAY 0.638298 (-1800 1675);
FORCEPROP 1 LAST TOLERANCE 5%
J 0
(-1675 1675);
DISPLAY 0.638298 (-1675 1675);
FORCEPROP 1 LAST WATTAGE 1/16W
J 2
(-1675 1625);
DISPLAY 0.638298 (-1675 1625);
FORCEPROP 2 LAST CDS_LIB pure_quanta
J 0
(-1975 1675);
DISPLAY INVISIBLE (-1975 1675);
FORCEPROP 1 LAST PATH I56
J 0
(-2025 1825);
DISPLAY 0.978723 (-2025 1825);
PAINT WHITE (-2025 1825);
DISPLAY INVISIBLE (-2025 1825);
FORCEPROP 1 LAST PART_NUMBER CS00002JB13
J 0
(-2175 1575);
DISPLAY 0.638298 (-2175 1575);
DISPLAY INVISIBLE (-2175 1575);
FORCEADD Q_RES..1
(-2125 1925);
FORCEPROP 1 LAST LOCATION PR6544
J 0
(-2175 1975);
DISPLAY 0.978723 (-2175 1975);
FORCEPROP 0 LAST $SEC 1
J 0
(-2175 2025);
DISPLAY 0.680851 (-2175 2025);
PAINT MONO (-2175 2025);
DISPLAY INVISIBLE (-2175 2025);
FORCEPROP 0 LAST CDS_SEC 1
J 0
(-2175 2025);
DISPLAY 0.680851 (-2175 2025);
DISPLAY INVISIBLE (-2175 2025);
FORCEPROP 1 LASTPIN (-2225 1925) $PN 1
J 0
(-2213 1937);
DISPLAY 0.787234 (-2213 1937);
PAINT MONO (-2213 1937);
FORCEPROP 1 LASTPIN (-2025 1925) $PN 2
J 0
(-2063 1937);
DISPLAY 0.787234 (-2063 1937);
PAINT MONO (-2063 1937);
FORCEPROP 1 LAST WATTAGE 1/16W
J 2
(-2250 1850);
DISPLAY 0.510638 (-2250 1850);
FORCEPROP 1 LAST MATERIAL CHIP
J 0
(-2500 1850);
DISPLAY 0.510638 (-2500 1850);
FORCEPROP 1 LAST TOLERANCE 5%
J 0
(-1950 1950);
DISPLAY 0.510638 (-1950 1950);
FORCEPROP 1 LAST VALUE 0
J 2
(-2000 1950);
DISPLAY 0.510638 (-2000 1950);
FORCEPROP 1 LAST PACK_TYPE 0402LF
J 0
(-1975 2050);
DISPLAY 0.510638 (-1975 2050);
DISPLAY INVISIBLE (-1975 2050);
FORCEPROP 2 LAST CDS_LIB pure_quanta
J 0
(-2125 1925);
DISPLAY INVISIBLE (-2125 1925);
FORCEPROP 1 LAST PATH I57
J 0
(-2175 2075);
DISPLAY 0.978723 (-2175 2075);
PAINT WHITE (-2175 2075);
DISPLAY INVISIBLE (-2175 2075);
FORCEPROP 1 LAST PART_NUMBER CS00002JB13
J 0
(-2225 1850);
DISPLAY 0.510638 (-2225 1850);
DISPLAY INVISIBLE (-2225 1850);
FORCEADD Q_RES..1
(-2125 2375);
FORCEPROP 1 LAST LOCATION PR6543
J 0
(-2175 2425);
DISPLAY 0.978723 (-2175 2425);
FORCEPROP 0 LAST $SEC 1
J 0
(-2175 2475);
DISPLAY 0.680851 (-2175 2475);
PAINT MONO (-2175 2475);
DISPLAY INVISIBLE (-2175 2475);
FORCEPROP 0 LAST CDS_SEC 1
J 0
(-2175 2475);
DISPLAY 0.680851 (-2175 2475);
DISPLAY INVISIBLE (-2175 2475);
FORCEPROP 1 LASTPIN (-2225 2375) $PN 1
J 0
(-2213 2387);
DISPLAY 0.787234 (-2213 2387);
PAINT MONO (-2213 2387);
FORCEPROP 1 LASTPIN (-2025 2375) $PN 2
J 0
(-2063 2387);
DISPLAY 0.787234 (-2063 2387);
PAINT MONO (-2063 2387);
FORCEPROP 1 LAST MATERIAL CHIP
J 0
(-2500 2300);
DISPLAY 0.510638 (-2500 2300);
FORCEPROP 1 LAST WATTAGE 1/16W
J 2
(-2250 2300);
DISPLAY 0.510638 (-2250 2300);
FORCEPROP 1 LAST VALUE 0
J 2
(-2000 2400);
DISPLAY 0.510638 (-2000 2400);
FORCEPROP 1 LAST TOLERANCE 5%
J 0
(-1950 2400);
DISPLAY 0.510638 (-1950 2400);
FORCEPROP 1 LAST PACK_TYPE 0402LF
J 0
(-1975 2500);
DISPLAY 0.510638 (-1975 2500);
DISPLAY INVISIBLE (-1975 2500);
FORCEPROP 2 LAST CDS_LIB pure_quanta
J 0
(-2125 2375);
DISPLAY INVISIBLE (-2125 2375);
FORCEPROP 1 LAST PATH I58
J 0
(-2175 2525);
DISPLAY 0.978723 (-2175 2525);
PAINT WHITE (-2175 2525);
DISPLAY INVISIBLE (-2175 2525);
FORCEPROP 1 LAST PART_NUMBER CS00002JB13
J 0
(-2225 2300);
DISPLAY 0.510638 (-2225 2300);
DISPLAY INVISIBLE (-2225 2300);
FORCEADD UNIVERSAL_GND..1
(-1750 1775);
FORCEPROP 3 LASTPIN (-1750 1825) SIG_NAME GND\g
J 0
(-1740 1835);
DISPLAY 0.659574 (-1740 1835);
PAINT MONO (-1740 1835);
DISPLAY INVISIBLE (-1740 1835);
FORCEPROP 2 LAST CDS_LIB pure_quanta_power
J 0
(-1750 1775);
DISPLAY INVISIBLE (-1750 1775);
FORCEPROP 1 LAST HDL_POWER GND
J 1
(-1725 1700);
DISPLAY 0.872340 (-1725 1700);
PAINT GREEN (-1725 1700);
DISPLAY INVISIBLE (-1725 1700);
FORCEPROP 1 LAST PATH I59
J 0
(-1675 1775);
DISPLAY 0.872340 (-1675 1775);
PAINT AQUA (-1675 1775);
DISPLAY INVISIBLE (-1675 1775);
FORCEADD VCC15..1
(-7000 750);
FORCEPROP 3 LASTPIN (-7000 700) SIG_NAME P5V_AUX\g
J 0
(-6990 710);
DISPLAY 0.659574 (-6990 710);
PAINT MONO (-6990 710);
DISPLAY INVISIBLE (-6990 710);
FORCEPROP 1 LAST HDL_POWER P5V_AUX
J 1
(-7000 800);
DISPLAY 0.617021 (-7000 800);
PAINT GREEN (-7000 800);
FORCEPROP 2 LAST CDS_LIB pure_quanta_power
J 0
(-7000 750);
DISPLAY INVISIBLE (-7000 750);
FORCEPROP 1 LAST PATH I6
J 0
(-6950 775);
DISPLAY 0.872340 (-6950 775);
PAINT AQUA (-6950 775);
DISPLAY INVISIBLE (-6950 775);
FORCEADD UNIVERSAL_GND..1
(-1750 2150);
FORCEPROP 3 LASTPIN (-1750 2200) SIG_NAME GND\g
J 0
(-1740 2210);
DISPLAY 0.659574 (-1740 2210);
PAINT MONO (-1740 2210);
DISPLAY INVISIBLE (-1740 2210);
FORCEPROP 2 LAST CDS_LIB pure_quanta_power
J 0
(-1750 2150);
DISPLAY INVISIBLE (-1750 2150);
FORCEPROP 1 LAST HDL_POWER GND
J 1
(-1725 2075);
DISPLAY 0.872340 (-1725 2075);
PAINT GREEN (-1725 2075);
DISPLAY INVISIBLE (-1725 2075);
FORCEPROP 1 LAST PATH I60
J 0
(-1675 2150);
DISPLAY 0.872340 (-1675 2150);
PAINT AQUA (-1675 2150);
DISPLAY INVISIBLE (-1675 2150);
FORCEADD UNIVERSAL_GND..1
(-5000 2650);
FORCEPROP 3 LASTPIN (-5000 2700) SIG_NAME GND\g
J 0
(-4990 2710);
DISPLAY 0.659574 (-4990 2710);
PAINT MONO (-4990 2710);
DISPLAY INVISIBLE (-4990 2710);
FORCEPROP 2 LAST CDS_LIB pure_quanta_power
J 0
(-5000 2650);
DISPLAY INVISIBLE (-5000 2650);
FORCEPROP 1 LAST HDL_POWER GND
J 1
(-4975 2575);
DISPLAY 0.872340 (-4975 2575);
PAINT GREEN (-4975 2575);
DISPLAY INVISIBLE (-4975 2575);
FORCEPROP 1 LAST PATH I61
J 0
(-4925 2650);
DISPLAY 0.872340 (-4925 2650);
PAINT AQUA (-4925 2650);
DISPLAY INVISIBLE (-4925 2650);
FORCEADD UNIVERSAL_GND..1
(-5000 2875);
FORCEPROP 3 LASTPIN (-5000 2925) SIG_NAME GND\g
J 0
(-4990 2935);
DISPLAY 0.659574 (-4990 2935);
PAINT MONO (-4990 2935);
DISPLAY INVISIBLE (-4990 2935);
FORCEPROP 2 LAST CDS_LIB pure_quanta_power
J 0
(-5000 2875);
DISPLAY INVISIBLE (-5000 2875);
FORCEPROP 1 LAST HDL_POWER GND
J 1
(-4975 2800);
DISPLAY 0.872340 (-4975 2800);
PAINT GREEN (-4975 2800);
DISPLAY INVISIBLE (-4975 2800);
FORCEPROP 1 LAST PATH I62
J 0
(-4925 2875);
DISPLAY 0.872340 (-4925 2875);
PAINT AQUA (-4925 2875);
DISPLAY INVISIBLE (-4925 2875);
FORCEADD UNIVERSAL_GND..1
R 1
(-4950 6325);
FORCEPROP 3 LASTPIN (-5000 6325) SIG_NAME GND\g
J 0
(-4990 6335);
DISPLAY 0.659574 (-4990 6335);
PAINT MONO (-4990 6335);
DISPLAY INVISIBLE (-4990 6335);
FORCEPROP 2 LAST CDS_LIB pure_quanta_power
J 0
(-4950 6325);
DISPLAY INVISIBLE (-4950 6325);
FORCEPROP 1 LAST HDL_POWER GND
R 1
J 1
(-4875 6350);
DISPLAY 0.872340 (-4875 6350);
PAINT GREEN (-4875 6350);
DISPLAY INVISIBLE (-4875 6350);
FORCEPROP 1 LAST PATH I63
R 1
J 0
(-4950 6400);
DISPLAY 0.872340 (-4950 6400);
PAINT AQUA (-4950 6400);
DISPLAY INVISIBLE (-4950 6400);
FORCEADD Q_RES..1
(-2125 2825);
FORCEPROP 1 LAST LOCATION PR6542
J 0
(-2175 2875);
DISPLAY 0.978723 (-2175 2875);
FORCEPROP 0 LAST $SEC 1
J 0
(-2175 2925);
DISPLAY 0.680851 (-2175 2925);
PAINT MONO (-2175 2925);
DISPLAY INVISIBLE (-2175 2925);
FORCEPROP 0 LAST CDS_SEC 1
J 0
(-2175 2925);
DISPLAY 0.680851 (-2175 2925);
DISPLAY INVISIBLE (-2175 2925);
FORCEPROP 1 LASTPIN (-2225 2825) $PN 1
J 0
(-2213 2837);
DISPLAY 0.787234 (-2213 2837);
PAINT MONO (-2213 2837);
FORCEPROP 1 LASTPIN (-2025 2825) $PN 2
J 0
(-2063 2837);
DISPLAY 0.787234 (-2063 2837);
PAINT MONO (-2063 2837);
FORCEPROP 1 LAST MATERIAL CHIP
J 0
(-2500 2750);
DISPLAY 0.510638 (-2500 2750);
FORCEPROP 1 LAST WATTAGE 1/16W
J 2
(-2250 2750);
DISPLAY 0.510638 (-2250 2750);
FORCEPROP 1 LAST TOLERANCE 5%
J 0
(-1950 2850);
DISPLAY 0.510638 (-1950 2850);
FORCEPROP 1 LAST VALUE 0
J 2
(-2000 2850);
DISPLAY 0.510638 (-2000 2850);
FORCEPROP 1 LAST PACK_TYPE 0402LF
J 0
(-1975 2950);
DISPLAY 0.510638 (-1975 2950);
DISPLAY INVISIBLE (-1975 2950);
FORCEPROP 2 LAST CDS_LIB pure_quanta
J 0
(-2125 2825);
DISPLAY INVISIBLE (-2125 2825);
FORCEPROP 1 LAST PATH I64
J 0
(-2175 2975);
DISPLAY 0.978723 (-2175 2975);
PAINT WHITE (-2175 2975);
DISPLAY INVISIBLE (-2175 2975);
FORCEPROP 1 LAST PART_NUMBER CS00002JB13
J 0
(-2225 2750);
DISPLAY 0.510638 (-2225 2750);
DISPLAY INVISIBLE (-2225 2750);
FORCEADD Q_RES..1
(-2125 3275);
FORCEPROP 1 LAST LOCATION PR6541
J 0
(-2175 3325);
DISPLAY 0.978723 (-2175 3325);
FORCEPROP 0 LAST $SEC 1
J 0
(-2175 3375);
DISPLAY 0.680851 (-2175 3375);
PAINT MONO (-2175 3375);
DISPLAY INVISIBLE (-2175 3375);
FORCEPROP 0 LAST CDS_SEC 1
J 0
(-2175 3375);
DISPLAY 0.680851 (-2175 3375);
DISPLAY INVISIBLE (-2175 3375);
FORCEPROP 1 LASTPIN (-2225 3275) $PN 1
J 0
(-2213 3287);
DISPLAY 0.787234 (-2213 3287);
PAINT MONO (-2213 3287);
FORCEPROP 1 LASTPIN (-2025 3275) $PN 2
J 0
(-2063 3287);
DISPLAY 0.787234 (-2063 3287);
PAINT MONO (-2063 3287);
FORCEPROP 1 LAST WATTAGE 1/16W
J 2
(-2250 3200);
DISPLAY 0.510638 (-2250 3200);
FORCEPROP 1 LAST MATERIAL CHIP
J 0
(-2500 3200);
DISPLAY 0.510638 (-2500 3200);
FORCEPROP 1 LAST TOLERANCE 5%
J 0
(-1950 3300);
DISPLAY 0.510638 (-1950 3300);
FORCEPROP 1 LAST VALUE 0
J 2
(-2000 3300);
DISPLAY 0.510638 (-2000 3300);
FORCEPROP 1 LAST PACK_TYPE 0402LF
J 0
(-1975 3400);
DISPLAY 0.510638 (-1975 3400);
DISPLAY INVISIBLE (-1975 3400);
FORCEPROP 2 LAST CDS_LIB pure_quanta
J 0
(-2125 3275);
DISPLAY INVISIBLE (-2125 3275);
FORCEPROP 1 LAST PATH I65
J 0
(-2175 3425);
DISPLAY 0.978723 (-2175 3425);
PAINT WHITE (-2175 3425);
DISPLAY INVISIBLE (-2175 3425);
FORCEPROP 1 LAST PART_NUMBER CS00002JB13
J 0
(-2225 3200);
DISPLAY 0.510638 (-2225 3200);
DISPLAY INVISIBLE (-2225 3200);
FORCEADD UNIVERSAL_GND..1
(-1750 2575);
FORCEPROP 3 LASTPIN (-1750 2625) SIG_NAME GND\g
J 0
(-1740 2635);
DISPLAY 0.659574 (-1740 2635);
PAINT MONO (-1740 2635);
DISPLAY INVISIBLE (-1740 2635);
FORCEPROP 2 LAST CDS_LIB pure_quanta_power
J 0
(-1750 2575);
DISPLAY INVISIBLE (-1750 2575);
FORCEPROP 1 LAST HDL_POWER GND
J 1
(-1725 2500);
DISPLAY 0.872340 (-1725 2500);
PAINT GREEN (-1725 2500);
DISPLAY INVISIBLE (-1725 2500);
FORCEPROP 1 LAST PATH I66
J 0
(-1675 2575);
DISPLAY 0.872340 (-1675 2575);
PAINT AQUA (-1675 2575);
DISPLAY INVISIBLE (-1675 2575);
FORCEADD UNIVERSAL_GND..1
(-1750 3025);
FORCEPROP 3 LASTPIN (-1750 3075) SIG_NAME GND\g
J 0
(-1740 3085);
DISPLAY 0.659574 (-1740 3085);
PAINT MONO (-1740 3085);
DISPLAY INVISIBLE (-1740 3085);
FORCEPROP 2 LAST CDS_LIB pure_quanta_power
J 0
(-1750 3025);
DISPLAY INVISIBLE (-1750 3025);
FORCEPROP 1 LAST HDL_POWER GND
J 1
(-1725 2950);
DISPLAY 0.872340 (-1725 2950);
PAINT GREEN (-1725 2950);
DISPLAY INVISIBLE (-1725 2950);
FORCEPROP 1 LAST PATH I67
J 0
(-1675 3025);
DISPLAY 0.872340 (-1675 3025);
PAINT AQUA (-1675 3025);
DISPLAY INVISIBLE (-1675 3025);
FORCEADD Q_RES..1
(-2125 3725);
FORCEPROP 1 LAST LOCATION PR6540
J 0
(-2175 3775);
DISPLAY 0.978723 (-2175 3775);
FORCEPROP 0 LAST $SEC 1
J 0
(-2175 3825);
DISPLAY 0.680851 (-2175 3825);
PAINT MONO (-2175 3825);
DISPLAY INVISIBLE (-2175 3825);
FORCEPROP 0 LAST CDS_SEC 1
J 0
(-2175 3825);
DISPLAY 0.680851 (-2175 3825);
DISPLAY INVISIBLE (-2175 3825);
FORCEPROP 1 LASTPIN (-2225 3725) $PN 1
J 0
(-2213 3737);
DISPLAY 0.787234 (-2213 3737);
PAINT MONO (-2213 3737);
FORCEPROP 1 LASTPIN (-2025 3725) $PN 2
J 0
(-2060 3735);
DISPLAY 0.787234 (-2060 3735);
PAINT MONO (-2060 3735);
FORCEPROP 1 LAST WATTAGE 1/16W
J 2
(-2250 3650);
DISPLAY 0.510638 (-2250 3650);
FORCEPROP 1 LAST VALUE 0
J 2
(-1975 3750);
DISPLAY 0.510638 (-1975 3750);
FORCEPROP 1 LAST TOLERANCE 5%
J 0
(-1925 3750);
DISPLAY 0.510638 (-1925 3750);
FORCEPROP 1 LAST MATERIAL CHIP
J 0
(-2500 3650);
DISPLAY 0.510638 (-2500 3650);
FORCEPROP 1 LAST PACK_TYPE 0402LF
J 0
(-1975 3850);
DISPLAY 0.510638 (-1975 3850);
DISPLAY INVISIBLE (-1975 3850);
FORCEPROP 2 LAST CDS_LIB pure_quanta
J 0
(-2125 3725);
DISPLAY INVISIBLE (-2125 3725);
FORCEPROP 1 LAST PATH I68
J 0
(-2175 3875);
DISPLAY 0.978723 (-2175 3875);
PAINT WHITE (-2175 3875);
DISPLAY INVISIBLE (-2175 3875);
FORCEPROP 1 LAST PART_NUMBER CS00002JB13
J 0
(-2225 3650);
DISPLAY 0.510638 (-2225 3650);
DISPLAY INVISIBLE (-2225 3650);
FORCEADD Q_RES..1
(-2125 4175);
FORCEPROP 1 LAST LOCATION PR6539
J 0
(-2175 4225);
DISPLAY 0.978723 (-2175 4225);
FORCEPROP 0 LAST $SEC 1
J 0
(-2175 4275);
DISPLAY 0.680851 (-2175 4275);
PAINT MONO (-2175 4275);
DISPLAY INVISIBLE (-2175 4275);
FORCEPROP 0 LAST CDS_SEC 1
J 0
(-2175 4275);
DISPLAY 0.680851 (-2175 4275);
DISPLAY INVISIBLE (-2175 4275);
FORCEPROP 1 LASTPIN (-2225 4175) $PN 1
J 0
(-2213 4187);
DISPLAY 0.787234 (-2213 4187);
PAINT MONO (-2213 4187);
FORCEPROP 1 LASTPIN (-2025 4175) $PN 2
J 0
(-2063 4187);
DISPLAY 0.787234 (-2063 4187);
PAINT MONO (-2063 4187);
FORCEPROP 1 LAST MATERIAL CHIP
J 0
(-2500 4100);
DISPLAY 0.510638 (-2500 4100);
FORCEPROP 1 LAST WATTAGE 1/16W
J 2
(-2250 4100);
DISPLAY 0.510638 (-2250 4100);
FORCEPROP 1 LAST TOLERANCE 5%
J 0
(-1925 4200);
DISPLAY 0.510638 (-1925 4200);
FORCEPROP 1 LAST VALUE 0
J 2
(-1975 4200);
DISPLAY 0.510638 (-1975 4200);
FORCEPROP 1 LAST PACK_TYPE 0402LF
J 0
(-1975 4300);
DISPLAY 0.510638 (-1975 4300);
DISPLAY INVISIBLE (-1975 4300);
FORCEPROP 2 LAST CDS_LIB pure_quanta
J 0
(-2125 4175);
DISPLAY INVISIBLE (-2125 4175);
FORCEPROP 1 LAST PATH I69
J 0
(-2175 4325);
DISPLAY 0.978723 (-2175 4325);
PAINT WHITE (-2175 4325);
DISPLAY INVISIBLE (-2175 4325);
FORCEPROP 1 LAST PART_NUMBER CS00002JB13
J 0
(-2225 4100);
DISPLAY 0.510638 (-2225 4100);
DISPLAY INVISIBLE (-2225 4100);
FORCEADD Q_RES..1
(-6700 600);
FORCEPROP 1 LAST LOCATION PR885
J 0
(-6975 600);
DISPLAY 0.787234 (-6975 600);
FORCEPROP 0 LAST $SEC 1
J 0
(-6900 650);
DISPLAY 0.680851 (-6900 650);
PAINT MONO (-6900 650);
DISPLAY INVISIBLE (-6900 650);
FORCEPROP 0 LAST CDS_SEC 1
J 0
(-6900 650);
DISPLAY 0.680851 (-6900 650);
DISPLAY INVISIBLE (-6900 650);
FORCEPROP 1 LASTPIN (-6800 600) $PN 1
J 0
(-6788 612);
DISPLAY 0.787234 (-6788 612);
PAINT MONO (-6788 612);
FORCEPROP 1 LASTPIN (-6600 600) $PN 2
J 0
(-6638 612);
DISPLAY 0.787234 (-6638 612);
PAINT MONO (-6638 612);
FORCEPROP 1 LAST MATERIAL EMPTY
J 0
(-6800 550);
DISPLAY 0.510638 (-6800 550);
FORCEPROP 1 LAST VALUE 5.36K
J 2
(-6400 600);
DISPLAY 0.510638 (-6400 600);
FORCEPROP 1 LAST WATTAGE 1/16W
J 2
(-6525 550);
DISPLAY 0.510638 (-6525 550);
FORCEPROP 1 LAST TOLERANCE 1%
J 0
(-6375 600);
DISPLAY 0.510638 (-6375 600);
FORCEPROP 1 LAST PACK_TYPE 0402LF
J 0
(-6475 550);
DISPLAY 0.510638 (-6475 550);
FORCEPROP 2 LAST CDS_LIB pure_quanta
J 0
(-6700 600);
DISPLAY INVISIBLE (-6700 600);
FORCEPROP 1 LAST PATH I7
J 0
(-6750 750);
DISPLAY 0.978723 (-6750 750);
PAINT WHITE (-6750 750);
DISPLAY INVISIBLE (-6750 750);
FORCEPROP 1 LAST PART_NUMBER CS25362FB02
J 0
(-6800 500);
DISPLAY 0.510638 (-6800 500);
DISPLAY INVISIBLE (-6800 500);
FORCEADD UNIVERSAL_GND..1
(-1750 3525);
FORCEPROP 3 LASTPIN (-1750 3575) SIG_NAME GND\g
J 0
(-1740 3585);
DISPLAY 0.659574 (-1740 3585);
PAINT MONO (-1740 3585);
DISPLAY INVISIBLE (-1740 3585);
FORCEPROP 2 LAST CDS_LIB pure_quanta_power
J 0
(-1750 3525);
DISPLAY INVISIBLE (-1750 3525);
FORCEPROP 1 LAST HDL_POWER GND
J 1
(-1725 3450);
DISPLAY 0.872340 (-1725 3450);
PAINT GREEN (-1725 3450);
DISPLAY INVISIBLE (-1725 3450);
FORCEPROP 1 LAST PATH I70
J 0
(-1675 3525);
DISPLAY 0.872340 (-1675 3525);
PAINT AQUA (-1675 3525);
DISPLAY INVISIBLE (-1675 3525);
FORCEADD UNIVERSAL_GND..1
(-1750 4025);
FORCEPROP 3 LASTPIN (-1750 4075) SIG_NAME GND\g
J 0
(-1740 4085);
DISPLAY 0.659574 (-1740 4085);
PAINT MONO (-1740 4085);
DISPLAY INVISIBLE (-1740 4085);
FORCEPROP 2 LAST CDS_LIB pure_quanta_power
J 0
(-1750 4025);
DISPLAY INVISIBLE (-1750 4025);
FORCEPROP 1 LAST HDL_POWER GND
J 1
(-1725 3950);
DISPLAY 0.872340 (-1725 3950);
PAINT GREEN (-1725 3950);
DISPLAY INVISIBLE (-1725 3950);
FORCEPROP 1 LAST PATH I71
J 0
(-1675 4025);
DISPLAY 0.872340 (-1675 4025);
PAINT AQUA (-1675 4025);
DISPLAY INVISIBLE (-1675 4025);
FORCEADD Q_CAP..1
(-2875 5500);
FORCEPROP 1 LAST LOCATION PC6546
J 0
(-2825 5600);
DISPLAY 0.808511 (-2825 5600);
FORCEPROP 0 LAST $SEC 1
J 0
(-2825 5650);
DISPLAY 0.680851 (-2825 5650);
PAINT MONO (-2825 5650);
DISPLAY INVISIBLE (-2825 5650);
FORCEPROP 0 LAST CDS_SEC 1
J 0
(-2825 5650);
DISPLAY 0.680851 (-2825 5650);
DISPLAY INVISIBLE (-2825 5650);
FORCEPROP 1 LASTPIN (-2875 5600) $PN 1
J 0
(-2865 5580);
DISPLAY 0.787234 (-2865 5580);
PAINT MONO (-2865 5580);
FORCEPROP 1 LASTPIN (-2875 5400) $PN 2
J 0
(-2865 5380);
DISPLAY 0.787234 (-2865 5380);
PAINT MONO (-2865 5380);
FORCEPROP 1 LAST VALUE 10UF
J 0
(-2825 5550);
DISPLAY 0.510638 (-2825 5550);
FORCEPROP 1 LAST VOLTAGE 6.3V
J 0
(-2825 5500);
DISPLAY 0.510638 (-2825 5500);
FORCEPROP 1 LAST TOLERANCE 20%
J 0
(-2825 5450);
DISPLAY 0.510638 (-2825 5450);
FORCEPROP 1 LAST MATERIAL X6S
J 0
(-2825 5400);
DISPLAY 0.510638 (-2825 5400);
FORCEPROP 1 LAST PACK_TYPE C0402
J 0
(-2825 5300);
DISPLAY 0.510638 (-2825 5300);
FORCEPROP 2 LAST CDS_LIB pure_quanta
J 0
(-2875 5500);
DISPLAY INVISIBLE (-2875 5500);
FORCEPROP 1 LAST PATH I72
J 0
(-2825 5650);
DISPLAY 0.978723 (-2825 5650);
PAINT WHITE (-2825 5650);
DISPLAY INVISIBLE (-2825 5650);
FORCEPROP 1 LAST PART_NUMBER CH6101MEB03
J 0
(-2825 5350);
DISPLAY 0.510638 (-2825 5350);
DISPLAY INVISIBLE (-2825 5350);
FORCEADD Q_CAP..1
(-2475 5500);
FORCEPROP 1 LAST LOCATION PC6545
J 0
(-2425 5600);
DISPLAY 0.787234 (-2425 5600);
FORCEPROP 0 LAST $SEC 1
J 0
(-2425 5650);
DISPLAY 0.680851 (-2425 5650);
PAINT MONO (-2425 5650);
DISPLAY INVISIBLE (-2425 5650);
FORCEPROP 0 LAST CDS_SEC 1
J 0
(-2425 5650);
DISPLAY 0.680851 (-2425 5650);
DISPLAY INVISIBLE (-2425 5650);
FORCEPROP 1 LASTPIN (-2475 5600) $PN 1
J 0
(-2465 5580);
DISPLAY 0.787234 (-2465 5580);
PAINT MONO (-2465 5580);
FORCEPROP 1 LASTPIN (-2475 5400) $PN 2
J 0
(-2465 5380);
DISPLAY 0.787234 (-2465 5380);
PAINT MONO (-2465 5380);
FORCEPROP 1 LAST VALUE 1UF
J 0
(-2425 5550);
DISPLAY 0.489362 (-2425 5550);
FORCEPROP 1 LAST VOLTAGE 16V
J 0
(-2425 5500);
DISPLAY 0.489362 (-2425 5500);
FORCEPROP 1 LAST TOLERANCE 10%
J 0
(-2425 5450);
DISPLAY 0.489362 (-2425 5450);
FORCEPROP 1 LAST PACK_TYPE C0402
J 0
(-2425 5300);
DISPLAY 0.489362 (-2425 5300);
FORCEPROP 1 LAST MATERIAL X6S
J 0
(-2425 5400);
DISPLAY 0.489362 (-2425 5400);
FORCEPROP 2 LAST CDS_LIB pure_quanta
J 0
(-2475 5500);
DISPLAY INVISIBLE (-2475 5500);
FORCEPROP 1 LAST PATH I73
J 0
(-2425 5650);
DISPLAY 0.978723 (-2425 5650);
PAINT WHITE (-2425 5650);
DISPLAY INVISIBLE (-2425 5650);
FORCEPROP 1 LAST PART_NUMBER CH5103KEB01
J 0
(-2425 5350);
DISPLAY 0.489362 (-2425 5350);
DISPLAY INVISIBLE (-2425 5350);
FORCEADD Q_CAP..1
(-2875 5975);
FORCEPROP 1 LAST LOCATION PC6543
J 0
(-2825 6075);
DISPLAY 0.808511 (-2825 6075);
FORCEPROP 0 LAST $SEC 1
J 0
(-2825 6125);
DISPLAY 0.680851 (-2825 6125);
PAINT MONO (-2825 6125);
DISPLAY INVISIBLE (-2825 6125);
FORCEPROP 0 LAST CDS_SEC 1
J 0
(-2825 6125);
DISPLAY 0.680851 (-2825 6125);
DISPLAY INVISIBLE (-2825 6125);
FORCEPROP 1 LASTPIN (-2875 6075) $PN 1
J 0
(-2865 6055);
DISPLAY 0.787234 (-2865 6055);
PAINT MONO (-2865 6055);
FORCEPROP 1 LASTPIN (-2875 5875) $PN 2
J 0
(-2865 5855);
DISPLAY 0.787234 (-2865 5855);
PAINT MONO (-2865 5855);
FORCEPROP 1 LAST PACK_TYPE C0402
J 0
(-2825 5775);
DISPLAY 0.510638 (-2825 5775);
FORCEPROP 1 LAST MATERIAL X7R
J 0
(-2825 5875);
DISPLAY 0.510638 (-2825 5875);
FORCEPROP 1 LAST TOLERANCE 10%
J 0
(-2825 5925);
DISPLAY 0.510638 (-2825 5925);
FORCEPROP 1 LAST VOLTAGE 50V
J 0
(-2825 5975);
DISPLAY 0.510638 (-2825 5975);
FORCEPROP 1 LAST VALUE 100NF
J 0
(-2825 6025);
DISPLAY 0.510638 (-2825 6025);
FORCEPROP 2 LAST CDS_LIB pure_quanta
J 0
(-2875 5975);
DISPLAY INVISIBLE (-2875 5975);
FORCEPROP 1 LAST PATH I74
J 0
(-2825 6125);
DISPLAY 0.978723 (-2825 6125);
PAINT WHITE (-2825 6125);
DISPLAY INVISIBLE (-2825 6125);
FORCEPROP 1 LAST PART_NUMBER CH4106K1B01
J 0
(-2825 5825);
DISPLAY 0.510638 (-2825 5825);
DISPLAY INVISIBLE (-2825 5825);
FORCEADD Q_CAP..1
(-2475 5975);
FORCEPROP 1 LAST LOCATION PC6544
J 0
(-2425 6075);
DISPLAY 0.808511 (-2425 6075);
FORCEPROP 0 LAST $SEC 1
J 0
(-2425 6125);
DISPLAY 0.680851 (-2425 6125);
PAINT MONO (-2425 6125);
DISPLAY INVISIBLE (-2425 6125);
FORCEPROP 0 LAST CDS_SEC 1
J 0
(-2425 6125);
DISPLAY 0.680851 (-2425 6125);
DISPLAY INVISIBLE (-2425 6125);
FORCEPROP 1 LASTPIN (-2475 6075) $PN 1
J 0
(-2465 6055);
DISPLAY 0.787234 (-2465 6055);
PAINT MONO (-2465 6055);
FORCEPROP 1 LASTPIN (-2475 5875) $PN 2
J 0
(-2465 5855);
DISPLAY 0.787234 (-2465 5855);
PAINT MONO (-2465 5855);
FORCEPROP 1 LAST VALUE 1UF
J 0
(-2425 6025);
DISPLAY 0.489362 (-2425 6025);
FORCEPROP 1 LAST VOLTAGE 16V
J 0
(-2425 5975);
DISPLAY 0.489362 (-2425 5975);
FORCEPROP 1 LAST TOLERANCE 10%
J 0
(-2425 5925);
DISPLAY 0.489362 (-2425 5925);
FORCEPROP 1 LAST MATERIAL X6S
J 0
(-2425 5875);
DISPLAY 0.489362 (-2425 5875);
FORCEPROP 1 LAST PACK_TYPE C0402
J 0
(-2425 5775);
DISPLAY 0.489362 (-2425 5775);
FORCEPROP 2 LAST CDS_LIB pure_quanta
J 0
(-2475 5975);
DISPLAY INVISIBLE (-2475 5975);
FORCEPROP 1 LAST PATH I75
J 0
(-2425 6125);
DISPLAY 0.978723 (-2425 6125);
PAINT WHITE (-2425 6125);
DISPLAY INVISIBLE (-2425 6125);
FORCEPROP 1 LAST PART_NUMBER CH5103KEB01
J 0
(-2425 5825);
DISPLAY 0.489362 (-2425 5825);
DISPLAY INVISIBLE (-2425 5825);
FORCEADD OFFPAGE..4
(-2175 4625);
FORCEPROP 2 LAST $XR0 366 
J 0
(-1989 4625);
DISPLAY 0.638298 (-1989 4625);
PAINT MONO (-1989 4625);
FORCEPROP 2 LAST CDS_LIB standard
J 0
(-2175 4625);
DISPLAY INVISIBLE (-2175 4625);
FORCEPROP 1 LAST OFFPAGE TRUE
J 0
(-1850 4500);
DISPLAY 0.872340 (-1850 4500);
PAINT GREEN (-1850 4500);
DISPLAY INVISIBLE (-1850 4500);
FORCEPROP 1 LAST COMMENT_BODY TRUE
J 0
(-2200 4525);
DISPLAY 0.872340 (-2200 4525);
PAINT GREEN (-2200 4525);
DISPLAY INVISIBLE (-2200 4525);
FORCEPROP 2 LAST PATH I76
J 0
(-2000 4700);
DISPLAY 0.680851 (-2000 4700);
DISPLAY INVISIBLE (-2000 4700);
FORCEADD OFFPAGE..2
(-2175 4725);
FORCEPROP 2 LAST $XR0 366 
J 0
(-1986 4725);
DISPLAY 0.638298 (-1986 4725);
PAINT MONO (-1986 4725);
FORCEPROP 2 LAST CDS_LIB standard
J 0
(-2175 4725);
DISPLAY INVISIBLE (-2175 4725);
FORCEPROP 1 LAST OFFPAGE TRUE
J 0
(-1850 4600);
DISPLAY 0.872340 (-1850 4600);
PAINT GREEN (-1850 4600);
DISPLAY INVISIBLE (-1850 4600);
FORCEPROP 1 LAST COMMENT_BODY TRUE
J 0
(-2220 4630);
DISPLAY 0.872340 (-2220 4630);
PAINT GREEN (-2220 4630);
DISPLAY INVISIBLE (-2220 4630);
FORCEPROP 2 LAST PATH I77
J 0
(-2000 4800);
DISPLAY 0.680851 (-2000 4800);
DISPLAY INVISIBLE (-2000 4800);
FORCEADD OFFPAGE..2
(-2175 5175);
FORCEPROP 2 LAST $XR0 366 
J 0
(-1986 5175);
DISPLAY 0.638298 (-1986 5175);
PAINT MONO (-1986 5175);
FORCEPROP 2 LAST CDS_LIB standard
J 0
(-2175 5175);
DISPLAY INVISIBLE (-2175 5175);
FORCEPROP 1 LAST OFFPAGE TRUE
J 0
(-1850 5050);
DISPLAY 0.872340 (-1850 5050);
PAINT GREEN (-1850 5050);
DISPLAY INVISIBLE (-1850 5050);
FORCEPROP 1 LAST COMMENT_BODY TRUE
J 0
(-2220 5080);
DISPLAY 0.872340 (-2220 5080);
PAINT GREEN (-2220 5080);
DISPLAY INVISIBLE (-2220 5080);
FORCEPROP 2 LAST PATH I78
J 0
(-2000 5250);
DISPLAY 0.680851 (-2000 5250);
DISPLAY INVISIBLE (-2000 5250);
FORCEADD OFFPAGE..4
(-2175 5075);
FORCEPROP 2 LAST $XR0 366 
J 0
(-1989 5075);
DISPLAY 0.638298 (-1989 5075);
PAINT MONO (-1989 5075);
FORCEPROP 2 LAST CDS_LIB standard
J 0
(-2175 5075);
DISPLAY INVISIBLE (-2175 5075);
FORCEPROP 1 LAST OFFPAGE TRUE
J 0
(-1850 4950);
DISPLAY 0.872340 (-1850 4950);
PAINT GREEN (-1850 4950);
DISPLAY INVISIBLE (-1850 4950);
FORCEPROP 1 LAST COMMENT_BODY TRUE
J 0
(-2200 4975);
DISPLAY 0.872340 (-2200 4975);
PAINT GREEN (-2200 4975);
DISPLAY INVISIBLE (-2200 4975);
FORCEPROP 2 LAST PATH I79
J 0
(-2000 5150);
DISPLAY 0.680851 (-2000 5150);
DISPLAY INVISIBLE (-2000 5150);
FORCEADD VCC15..1
(-6700 950);
FORCEPROP 3 LASTPIN (-6700 900) SIG_NAME P12V_AUX\g
J 0
(-6690 910);
DISPLAY 0.659574 (-6690 910);
PAINT MONO (-6690 910);
DISPLAY INVISIBLE (-6690 910);
FORCEPROP 1 LAST HDL_POWER P12V_AUX
J 1
(-6700 1000);
DISPLAY 0.617021 (-6700 1000);
PAINT GREEN (-6700 1000);
FORCEPROP 2 LAST CDS_LIB pure_quanta_power
J 0
(-6700 950);
DISPLAY INVISIBLE (-6700 950);
FORCEPROP 1 LAST PATH I8
J 0
(-6650 975);
DISPLAY 0.872340 (-6650 975);
PAINT AQUA (-6650 975);
DISPLAY INVISIBLE (-6650 975);
FORCEADD UNIVERSAL_GND..1
R 3
(-2025 5300);
FORCEPROP 3 LASTPIN (-2075 5300) SIG_NAME GND\g
J 0
(-2065 5310);
DISPLAY 0.659574 (-2065 5310);
PAINT MONO (-2065 5310);
DISPLAY INVISIBLE (-2065 5310);
FORCEPROP 2 LAST CDS_LIB pure_quanta_power
J 0
(-2025 5300);
DISPLAY INVISIBLE (-2025 5300);
FORCEPROP 1 LAST HDL_POWER GND
R 1
J 1
(-1950 5275);
DISPLAY 0.872340 (-1950 5275);
PAINT GREEN (-1950 5275);
DISPLAY INVISIBLE (-1950 5275);
FORCEPROP 1 LAST PATH I80
R 1
J 2
(-2025 5225);
DISPLAY 0.872340 (-2025 5225);
PAINT AQUA (-2025 5225);
DISPLAY INVISIBLE (-2025 5225);
FORCEADD UNIVERSAL_GND..1
R 3
(-2025 5775);
FORCEPROP 3 LASTPIN (-2075 5775) SIG_NAME GND\g
J 0
(-2065 5785);
DISPLAY 0.659574 (-2065 5785);
PAINT MONO (-2065 5785);
DISPLAY INVISIBLE (-2065 5785);
FORCEPROP 2 LAST CDS_LIB pure_quanta_power
J 0
(-2025 5775);
DISPLAY INVISIBLE (-2025 5775);
FORCEPROP 1 LAST HDL_POWER GND
R 1
J 1
(-1950 5750);
DISPLAY 0.872340 (-1950 5750);
PAINT GREEN (-1950 5750);
DISPLAY INVISIBLE (-1950 5750);
FORCEPROP 1 LAST PATH I81
R 1
J 2
(-2025 5700);
DISPLAY 0.872340 (-2025 5700);
PAINT AQUA (-2025 5700);
DISPLAY INVISIBLE (-2025 5700);
FORCEADD OFFPAGE..2
(-2025 5700);
FORCEPROP 2 LAST $XR0 366 
J 0
(-1836 5700);
DISPLAY 0.638298 (-1836 5700);
PAINT MONO (-1836 5700);
FORCEPROP 2 LAST CDS_LIB standard
J 0
(-2025 5700);
DISPLAY INVISIBLE (-2025 5700);
FORCEPROP 1 LAST OFFPAGE TRUE
J 0
(-1700 5575);
DISPLAY 0.872340 (-1700 5575);
PAINT GREEN (-1700 5575);
DISPLAY INVISIBLE (-1700 5575);
FORCEPROP 1 LAST COMMENT_BODY TRUE
J 0
(-2070 5605);
DISPLAY 0.872340 (-2070 5605);
PAINT GREEN (-2070 5605);
DISPLAY INVISIBLE (-2070 5605);
FORCEPROP 2 LAST PATH I82
J 0
(-1850 5775);
DISPLAY 0.680851 (-1850 5775);
DISPLAY INVISIBLE (-1850 5775);
FORCEADD Q_RES..1
(-2150 6175);
FORCEPROP 1 LAST LOCATION PR6538
J 0
(-2225 6350);
DISPLAY 0.808511 (-2225 6350);
FORCEPROP 0 LAST $SEC 1
J 0
(-2225 6400);
DISPLAY 0.680851 (-2225 6400);
PAINT MONO (-2225 6400);
DISPLAY INVISIBLE (-2225 6400);
FORCEPROP 0 LAST CDS_SEC 1
J 0
(-2225 6400);
DISPLAY 0.680851 (-2225 6400);
DISPLAY INVISIBLE (-2225 6400);
FORCEPROP 1 LASTPIN (-2250 6175) $PN 1
J 0
(-2238 6187);
DISPLAY 0.787234 (-2238 6187);
PAINT MONO (-2238 6187);
FORCEPROP 1 LASTPIN (-2050 6175) $PN 2
J 0
(-2088 6187);
DISPLAY 0.787234 (-2088 6187);
PAINT MONO (-2088 6187);
FORCEPROP 1 LAST WATTAGE 1/16W
J 2
(-2025 6300);
DISPLAY 0.510638 (-2025 6300);
FORCEPROP 1 LAST VALUE 1
J 2
(-1975 6175);
DISPLAY 0.510638 (-1975 6175);
FORCEPROP 1 LAST MATERIAL CHIP
J 0
(-2275 6300);
DISPLAY 0.510638 (-2275 6300);
FORCEPROP 1 LAST PACK_TYPE 0402LF
J 0
(-2000 6300);
DISPLAY 0.510638 (-2000 6300);
FORCEPROP 1 LAST TOLERANCE 1%
J 0
(-1925 6175);
DISPLAY 0.510638 (-1925 6175);
FORCEPROP 2 LAST CDS_LIB pure_quanta
J 0
(-2150 6175);
DISPLAY INVISIBLE (-2150 6175);
FORCEPROP 1 LAST PATH I83
J 0
(-2200 6325);
DISPLAY 0.978723 (-2200 6325);
PAINT WHITE (-2200 6325);
DISPLAY INVISIBLE (-2200 6325);
FORCEPROP 1 LAST PART_NUMBER CS-1002FB04
J 0
(-2275 6250);
DISPLAY 0.510638 (-2275 6250);
DISPLAY INVISIBLE (-2275 6250);
FORCEADD VCC15..1
(-1675 6300);
FORCEPROP 3 LASTPIN (-1675 6250) SIG_NAME P3V3_AUX\g
J 0
(-1665 6260);
DISPLAY 0.659574 (-1665 6260);
PAINT MONO (-1665 6260);
DISPLAY INVISIBLE (-1665 6260);
FORCEPROP 1 LAST HDL_POWER P3V3_AUX
J 1
(-1675 6350);
DISPLAY 0.617021 (-1675 6350);
PAINT GREEN (-1675 6350);
FORCEPROP 2 LAST CDS_LIB pure_quanta_power
J 0
(-1675 6300);
DISPLAY INVISIBLE (-1675 6300);
FORCEPROP 1 LAST PATH I84
J 0
(-1625 6325);
DISPLAY 0.872340 (-1625 6325);
PAINT AQUA (-1625 6325);
DISPLAY INVISIBLE (-1625 6325);
FORCEADD OFFPAGE..4
(-625 975);
FORCEPROP 2 LAST $XR0 366 
J 0
(-439 975);
DISPLAY 0.638298 (-439 975);
PAINT MONO (-439 975);
FORCEPROP 2 LAST CDS_LIB standard
J 0
(-625 975);
DISPLAY INVISIBLE (-625 975);
FORCEPROP 1 LAST OFFPAGE TRUE
J 0
(-300 850);
DISPLAY 0.872340 (-300 850);
PAINT GREEN (-300 850);
DISPLAY INVISIBLE (-300 850);
FORCEPROP 1 LAST COMMENT_BODY TRUE
J 0
(-650 875);
DISPLAY 0.872340 (-650 875);
PAINT GREEN (-650 875);
DISPLAY INVISIBLE (-650 875);
FORCEPROP 2 LAST PATH I85
J 0
(-450 1050);
DISPLAY 0.680851 (-450 1050);
DISPLAY INVISIBLE (-450 1050);
FORCEADD Q_RES..2
(-750 1900);
FORCEPROP 1 LAST LOCATION PR6812
J 0
(-705 2025);
DISPLAY 0.787234 (-705 2025);
FORCEPROP 0 LAST $SEC 1
J 0
(-700 2075);
DISPLAY 0.680851 (-700 2075);
PAINT MONO (-700 2075);
DISPLAY INVISIBLE (-700 2075);
FORCEPROP 0 LAST CDS_SEC 1
J 0
(-700 2075);
DISPLAY 0.680851 (-700 2075);
DISPLAY INVISIBLE (-700 2075);
FORCEPROP 1 LASTPIN (-750 2000) $PN 1
J 0
(-745 1962);
DISPLAY 0.787234 (-745 1962);
PAINT MONO (-745 1962);
FORCEPROP 1 LASTPIN (-750 1800) $PN 2
J 0
(-745 1810);
DISPLAY 0.787234 (-745 1810);
PAINT MONO (-745 1810);
FORCEPROP 1 LAST WATTAGE 1/16W
J 0
(-700 1875);
DISPLAY 0.510638 (-700 1875);
FORCEPROP 1 LAST MATERIAL CHIP
J 0
(-700 1825);
DISPLAY 0.510638 (-700 1825);
FORCEPROP 1 LAST TOLERANCE 1%
J 0
(-695 1925);
DISPLAY 0.510638 (-695 1925);
FORCEPROP 1 LAST PACK_TYPE 0402LF
J 0
(-700 1725);
DISPLAY 0.510638 (-700 1725);
FORCEPROP 1 LAST VALUE 1K
J 0
(-695 1975);
DISPLAY 0.510638 (-695 1975);
FORCEPROP 2 LAST CDS_LIB pure_quanta
J 0
(-750 1900);
DISPLAY INVISIBLE (-750 1900);
FORCEPROP 1 LAST PATH I86
J 0
(-700 2075);
DISPLAY 0.978723 (-700 2075);
PAINT WHITE (-700 2075);
DISPLAY INVISIBLE (-700 2075);
FORCEPROP 1 LAST PART_NUMBER CS21002FB06
J 0
(-700 1775);
DISPLAY 0.510638 (-700 1775);
DISPLAY INVISIBLE (-700 1775);
FORCEADD VCC15..1
(-750 2125);
FORCEPROP 3 LASTPIN (-750 2075) SIG_NAME P3V3_AUX\g
J 0
(-740 2085);
DISPLAY 0.659574 (-740 2085);
PAINT MONO (-740 2085);
DISPLAY INVISIBLE (-740 2085);
FORCEPROP 1 LAST HDL_POWER P3V3_AUX
J 1
(-750 2175);
DISPLAY 0.617021 (-750 2175);
PAINT GREEN (-750 2175);
FORCEPROP 2 LAST CDS_LIB pure_quanta_power
J 0
(-750 2125);
DISPLAY INVISIBLE (-750 2125);
FORCEPROP 1 LAST PATH I87
J 0
(-700 2150);
DISPLAY 0.872340 (-700 2150);
PAINT AQUA (-700 2150);
DISPLAY INVISIBLE (-700 2150);
FORCEADD ISL69260IRAZT..1
(-4125 3425);
FORCEPROP 1 LAST LOCATION PU6510
J 0
(-4670 6477);
DISPLAY 0.617021 (-4670 6477);
PAINT GREEN (-4670 6477);
FORCEPROP 2 LAST SEC 1
J 0
(-4650 6525);
DISPLAY 0.680851 (-4650 6525);
PAINT MONO (-4650 6525);
DISPLAY INVISIBLE (-4650 6525);
FORCEPROP 2 LASTPIN (-4800 1075) $PN 34
J 2
(-4810 1085);
DISPLAY 0.680851 (-4810 1085);
PAINT MONO (-4810 1085);
FORCEPROP 2 LASTPIN (-4800 2175) $PN 33
J 2
(-4810 2185);
DISPLAY 0.680851 (-4810 2185);
PAINT MONO (-4810 2185);
FORCEPROP 2 LASTPIN (-3450 1925) $PN 30
J 0
(-3440 1935);
DISPLAY 0.680851 (-3440 1935);
PAINT MONO (-3440 1935);
FORCEPROP 2 LASTPIN (-3450 2375) $PN 29
J 0
(-3440 2385);
DISPLAY 0.680851 (-3440 2385);
PAINT MONO (-3440 2385);
FORCEPROP 2 LASTPIN (-3450 2825) $PN 28
J 0
(-3440 2835);
DISPLAY 0.680851 (-3440 2835);
PAINT MONO (-3440 2835);
FORCEPROP 2 LASTPIN (-3450 3275) $PN 27
J 0
(-3440 3285);
DISPLAY 0.680851 (-3440 3285);
PAINT MONO (-3440 3285);
FORCEPROP 2 LASTPIN (-3450 3725) $PN 26
J 0
(-3440 3735);
DISPLAY 0.680851 (-3440 3735);
PAINT MONO (-3440 3735);
FORCEPROP 2 LASTPIN (-3450 4175) $PN 25
J 0
(-3440 4185);
DISPLAY 0.680851 (-3440 4185);
PAINT MONO (-3440 4185);
FORCEPROP 2 LASTPIN (-3450 4625) $PN 24
J 0
(-3440 4635);
DISPLAY 0.680851 (-3440 4635);
PAINT MONO (-3440 4635);
FORCEPROP 2 LASTPIN (-3450 5075) $PN 23
J 0
(-3440 5085);
DISPLAY 0.680851 (-3440 5085);
PAINT MONO (-3440 5085);
FORCEPROP 2 LASTPIN (-4800 6025) $PN 13
J 2
(-4810 6035);
DISPLAY 0.680851 (-4810 6035);
PAINT MONO (-4810 6035);
FORCEPROP 2 LASTPIN (-4800 1775) $PN 20
J 2
(-4810 1785);
DISPLAY 0.680851 (-4810 1785);
PAINT MONO (-4810 1785);
FORCEPROP 2 LASTPIN (-4800 6175) $PN 12
J 2
(-4810 6185);
DISPLAY 0.680851 (-4810 6185);
PAINT MONO (-4810 6185);
FORCEPROP 2 LASTPIN (-4800 1375) $PN 16
J 2
(-4810 1385);
DISPLAY 0.680851 (-4810 1385);
PAINT MONO (-4810 1385);
FORCEPROP 2 LASTPIN (-4800 5025) $PN 10
J 2
(-4810 5035);
DISPLAY 0.680851 (-4810 5035);
PAINT MONO (-4810 5035);
FORCEPROP 2 LASTPIN (-4800 4875) $PN 9
J 2
(-4810 4885);
DISPLAY 0.680851 (-4810 4885);
PAINT MONO (-4810 4885);
FORCEPROP 2 LASTPIN (-3450 2025) $PN 1
J 0
(-3440 2035);
DISPLAY 0.680851 (-3440 2035);
PAINT MONO (-3440 2035);
FORCEPROP 2 LASTPIN (-3450 2475) $PN 2
J 0
(-3440 2485);
DISPLAY 0.680851 (-3440 2485);
PAINT MONO (-3440 2485);
FORCEPROP 2 LASTPIN (-3450 2925) $PN 3
J 0
(-3440 2935);
DISPLAY 0.680851 (-3440 2935);
PAINT MONO (-3440 2935);
FORCEPROP 2 LASTPIN (-3450 3375) $PN 4
J 0
(-3440 3385);
DISPLAY 0.680851 (-3440 3385);
PAINT MONO (-3440 3385);
FORCEPROP 2 LASTPIN (-3450 3825) $PN 5
J 0
(-3440 3835);
DISPLAY 0.680851 (-3440 3835);
PAINT MONO (-3440 3835);
FORCEPROP 2 LASTPIN (-3450 4275) $PN 6
J 0
(-3440 4285);
DISPLAY 0.680851 (-3440 4285);
PAINT MONO (-3440 4285);
FORCEPROP 2 LASTPIN (-3450 4725) $PN 7
J 0
(-3440 4735);
DISPLAY 0.680851 (-3440 4735);
PAINT MONO (-3440 4735);
FORCEPROP 2 LASTPIN (-3450 5175) $PN 8
J 0
(-3440 5185);
DISPLAY 0.680851 (-3440 5185);
PAINT MONO (-3440 5185);
FORCEPROP 2 LASTPIN (-4800 3875) $PN 22
J 2
(-4810 3885);
DISPLAY 0.680851 (-4810 3885);
PAINT MONO (-4810 3885);
FORCEPROP 2 LASTPIN (-4800 2775) $PN 31
J 2
(-4810 2785);
DISPLAY 0.680851 (-4810 2785);
PAINT MONO (-4810 2785);
FORCEPROP 2 LASTPIN (-4800 5725) $PN 17
J 2
(-4810 5735);
DISPLAY 0.680851 (-4810 5735);
PAINT MONO (-4810 5735);
FORCEPROP 2 LASTPIN (-4800 5575) $PN 18
J 2
(-4810 5585);
DISPLAY 0.680851 (-4810 5585);
PAINT MONO (-4810 5585);
FORCEPROP 2 LASTPIN (-3450 975) $PN 35
J 0
(-3440 985);
DISPLAY 0.680851 (-3440 985);
PAINT MONO (-3440 985);
FORCEPROP 2 LASTPIN (-3450 1275) $PN 36
J 0
(-3440 1285);
DISPLAY 0.680851 (-3440 1285);
PAINT MONO (-3440 1285);
FORCEPROP 2 LASTPIN (-4800 625) $PN TH
J 2
(-4810 635);
DISPLAY 0.680851 (-4810 635);
PAINT MONO (-4810 635);
FORCEPROP 2 LASTPIN (-3450 6175) $PN 39
J 0
(-3440 6185);
DISPLAY 0.680851 (-3440 6185);
PAINT MONO (-3440 6185);
FORCEPROP 2 LASTPIN (-3450 5875) $PN 40
J 0
(-3440 5885);
DISPLAY 0.680851 (-3440 5885);
PAINT MONO (-3440 5885);
FORCEPROP 2 LASTPIN (-4800 4125) $PN 21
J 2
(-4810 4135);
DISPLAY 0.680851 (-4810 4135);
PAINT MONO (-4810 4135);
FORCEPROP 2 LASTPIN (-4800 3025) $PN 32
J 2
(-4810 3035);
DISPLAY 0.680851 (-4810 3035);
PAINT MONO (-4810 3035);
FORCEPROP 2 LASTPIN (-4800 1925) $PN 15
J 2
(-4810 1935);
DISPLAY 0.680851 (-4810 1935);
PAINT MONO (-4810 1935);
FORCEPROP 2 LASTPIN (-4800 4725) $PN 11
J 2
(-4810 4735);
DISPLAY 0.680851 (-4810 4735);
PAINT MONO (-4810 4735);
FORCEPROP 2 LASTPIN (-4800 5425) $PN 19
J 2
(-4810 5435);
DISPLAY 0.680851 (-4810 5435);
PAINT MONO (-4810 5435);
FORCEPROP 2 LASTPIN (-3450 1675) $PN 14
J 0
(-3440 1685);
DISPLAY 0.680851 (-3440 1685);
PAINT MONO (-3440 1685);
FORCEPROP 2 LASTPIN (-4800 725) $PN 38
J 2
(-4810 735);
DISPLAY 0.680851 (-4810 735);
PAINT MONO (-4810 735);
FORCEPROP 2 LASTPIN (-4800 825) $PN 37
J 2
(-4810 835);
DISPLAY 0.680851 (-4810 835);
PAINT MONO (-4810 835);
FORCEPROP 2 LAST PART_TYPE SMLF
J 0
(-4175 6425);
DISPLAY 0.638298 (-4175 6425);
FORCEPROP 2 LAST VALUE ISL69260IRAZ-T
J 0
(-4175 6375);
DISPLAY 0.617021 (-4175 6375);
FORCEPROP 1 LAST MATERIAL IC
J 0
(-4670 6283);
DISPLAY 0.617021 (-4670 6283);
PAINT GREEN (-4670 6283);
FORCEPROP 2 LAST CDS_LIB pure_quanta
J 0
(-4125 3425);
DISPLAY INVISIBLE (-4125 3425);
FORCEPROP 1 LAST CDS_LMAN_SYM_OUTLINE -550,2850,500,-2850
J 0
(-4125 3425);
DISPLAY 0.468085 (-4125 3425);
PAINT GREEN (-4125 3425);
DISPLAY INVISIBLE (-4125 3425);
FORCEPROP 1 LAST NEEDS_NO_SIZE TRUE
J 0
(-4125 3425);
DISPLAY 0.723404 (-4125 3425);
PAINT GREEN (-4125 3425);
DISPLAY INVISIBLE (-4125 3425);
FORCEPROP 2 LAST SEC_TYPE 
J 0
(-4650 6525);
DISPLAY 0.680851 (-4650 6525);
DISPLAY INVISIBLE (-4650 6525);
FORCEPROP 1 LAST PATH I88
J 0
(-4125 3425);
DISPLAY 0.723404 (-4125 3425);
PAINT GREEN (-4125 3425);
DISPLAY INVISIBLE (-4125 3425);
FORCEPROP 1 LAST PART_NUMBER AL069260000
J 0
(-4670 6370);
DISPLAY 0.617021 (-4670 6370);
PAINT GREEN (-4670 6370);
DISPLAY INVISIBLE (-4670 6370);
FORCEADD Q_RES..1
(-6475 4725);
FORCEPROP 1 LAST LOCATION R660
J 0
(-6725 4725);
DISPLAY 0.638298 (-6725 4725);
FORCEPROP 0 LAST $SEC 1
J 0
(-6525 4775);
DISPLAY 0.680851 (-6525 4775);
PAINT MONO (-6525 4775);
DISPLAY INVISIBLE (-6525 4775);
FORCEPROP 0 LAST CDS_SEC 1
J 0
(-6525 4775);
DISPLAY 0.680851 (-6525 4775);
DISPLAY INVISIBLE (-6525 4775);
FORCEPROP 1 LASTPIN (-6575 4725) $PN 1
J 0
(-6563 4737);
DISPLAY 0.787234 (-6563 4737);
PAINT MONO (-6563 4737);
FORCEPROP 1 LASTPIN (-6375 4725) $PN 2
J 0
(-6413 4737);
DISPLAY 0.787234 (-6413 4737);
PAINT MONO (-6413 4737);
FORCEPROP 1 LAST TOLERANCE 1%
J 0
(-6200 4725);
DISPLAY 0.510638 (-6200 4725);
FORCEPROP 1 LAST VALUE 4.7K
J 2
(-6250 4725);
DISPLAY 0.510638 (-6250 4725);
FORCEPROP 1 LAST MATERIAL EMPTY
J 0
(-6525 4750);
DISPLAY 0.510638 (-6525 4750);
FORCEPROP 1 LAST PACK_TYPE 0402LF
J 0
(-6250 4875);
DISPLAY 0.510638 (-6250 4875);
DISPLAY INVISIBLE (-6250 4875);
FORCEPROP 1 LAST WATTAGE 1/16W
J 2
(-6300 4875);
DISPLAY 0.510638 (-6300 4875);
DISPLAY INVISIBLE (-6300 4875);
FORCEPROP 2 LAST CDS_LIB pure_quanta
J 0
(-6475 4725);
DISPLAY INVISIBLE (-6475 4725);
FORCEPROP 1 LAST PATH I89
J 0
(-6525 4875);
DISPLAY 0.978723 (-6525 4875);
PAINT WHITE (-6525 4875);
DISPLAY INVISIBLE (-6525 4875);
FORCEPROP 1 LAST PART_NUMBER CS24702FB06
J 0
(-6575 4825);
DISPLAY 0.510638 (-6575 4825);
DISPLAY INVISIBLE (-6575 4825);
FORCEADD Q_RES..2
R 2
(-7575 5750);
FORCEPROP 1 LAST LOCATION R6787
J 2
(-7600 5850);
DISPLAY 0.808511 (-7600 5850);
FORCEPROP 0 LAST $SEC 1
J 0
(-7600 5900);
DISPLAY 0.680851 (-7600 5900);
PAINT MONO (-7600 5900);
DISPLAY INVISIBLE (-7600 5900);
FORCEPROP 0 LAST CDS_SEC 1
J 0
(-7600 5900);
DISPLAY 0.680851 (-7600 5900);
DISPLAY INVISIBLE (-7600 5900);
FORCEPROP 1 LASTPIN (-7575 5850) $PN 1
J 2
(-7580 5812);
DISPLAY 0.787234 (-7580 5812);
PAINT MONO (-7580 5812);
FORCEPROP 1 LASTPIN (-7575 5650) $PN 2
J 2
(-7580 5660);
DISPLAY 0.787234 (-7580 5660);
PAINT MONO (-7580 5660);
FORCEPROP 1 LAST VALUE 1K
J 2
(-7630 5800);
DISPLAY 0.510638 (-7630 5800);
FORCEPROP 1 LAST TOLERANCE 1%
J 2
(-7630 5750);
DISPLAY 0.510638 (-7630 5750);
FORCEPROP 1 LAST WATTAGE 1/16W
J 2
(-7625 5700);
DISPLAY 0.510638 (-7625 5700);
FORCEPROP 1 LAST PACK_TYPE 0402LF
J 2
(-7625 5550);
DISPLAY 0.510638 (-7625 5550);
FORCEPROP 1 LAST MATERIAL CHIP
J 2
(-7625 5650);
DISPLAY 0.510638 (-7625 5650);
FORCEPROP 2 LAST CDS_LIB pure_quanta
J 0
(-7575 5750);
DISPLAY INVISIBLE (-7575 5750);
FORCEPROP 1 LAST PATH I90
J 2
(-7625 5925);
DISPLAY 0.978723 (-7625 5925);
PAINT WHITE (-7625 5925);
DISPLAY INVISIBLE (-7625 5925);
FORCEPROP 1 LAST PART_NUMBER CS21002FB06
J 2
(-7625 5600);
DISPLAY 0.510638 (-7625 5600);
DISPLAY INVISIBLE (-7625 5600);
FORCEADD UNIVERSAL_GND..1
(-7575 5450);
FORCEPROP 3 LASTPIN (-7575 5500) SIG_NAME GND\g
J 0
(-7565 5510);
DISPLAY 0.659574 (-7565 5510);
PAINT MONO (-7565 5510);
DISPLAY INVISIBLE (-7565 5510);
FORCEPROP 2 LAST CDS_LIB pure_quanta_power
J 0
(-7575 5450);
DISPLAY INVISIBLE (-7575 5450);
FORCEPROP 1 LAST HDL_POWER GND
J 1
(-7550 5375);
DISPLAY 0.872340 (-7550 5375);
PAINT GREEN (-7550 5375);
DISPLAY INVISIBLE (-7550 5375);
FORCEPROP 1 LAST PATH I91
J 0
(-7500 5450);
DISPLAY 0.872340 (-7500 5450);
PAINT AQUA (-7500 5450);
DISPLAY INVISIBLE (-7500 5450);
FORCEADD Q_RES..1
(-6325 6325);
FORCEPROP 1 LAST LOCATION R656
J 0
(-6575 6325);
DISPLAY 0.638298 (-6575 6325);
FORCEPROP 0 LAST $SEC 1
J 0
(-6100 6500);
DISPLAY 0.680851 (-6100 6500);
PAINT MONO (-6100 6500);
DISPLAY INVISIBLE (-6100 6500);
FORCEPROP 0 LAST CDS_SEC 1
J 0
(-6100 6500);
DISPLAY 0.680851 (-6100 6500);
DISPLAY INVISIBLE (-6100 6500);
FORCEPROP 1 LASTPIN (-6425 6325) $PN 1
J 0
(-6413 6337);
DISPLAY 0.787234 (-6413 6337);
PAINT MONO (-6413 6337);
FORCEPROP 1 LASTPIN (-6225 6325) $PN 2
J 0
(-6263 6337);
DISPLAY 0.787234 (-6263 6337);
PAINT MONO (-6263 6337);
FORCEPROP 1 LAST VALUE 1K
J 2
(-6100 6325);
DISPLAY 0.510638 (-6100 6325);
FORCEPROP 1 LAST PACK_TYPE 0402LF
J 0
(-6100 6475);
DISPLAY 0.510638 (-6100 6475);
FORCEPROP 1 LAST WATTAGE 1/16W
J 2
(-6150 6475);
DISPLAY 0.510638 (-6150 6475);
FORCEPROP 1 LAST MATERIAL EMPTY
J 0
(-6425 6475);
DISPLAY 0.510638 (-6425 6475);
FORCEPROP 1 LAST TOLERANCE 1%
J 0
(-6050 6325);
DISPLAY 0.510638 (-6050 6325);
FORCEPROP 2 LAST CDS_LIB pure_quanta
J 0
(-6325 6325);
DISPLAY INVISIBLE (-6325 6325);
FORCEPROP 1 LAST PATH I92
J 0
(-6375 6475);
DISPLAY 0.978723 (-6375 6475);
PAINT WHITE (-6375 6475);
DISPLAY INVISIBLE (-6375 6475);
FORCEPROP 1 LAST PART_NUMBER CS21002FB06
J 0
(-6425 6425);
DISPLAY 0.510638 (-6425 6425);
DISPLAY INVISIBLE (-6425 6425);
FORCEADD Q_RES..1
(-7200 6325);
FORCEPROP 1 LAST LOCATION R6861
J 0
(-7475 6325);
DISPLAY 0.638298 (-7475 6325);
FORCEPROP 0 LAST $SEC 1
J 0
(-7050 6450);
DISPLAY 0.680851 (-7050 6450);
PAINT MONO (-7050 6450);
DISPLAY INVISIBLE (-7050 6450);
FORCEPROP 0 LAST CDS_SEC 1
J 0
(-7050 6450);
DISPLAY 0.680851 (-7050 6450);
DISPLAY INVISIBLE (-7050 6450);
FORCEPROP 1 LASTPIN (-7300 6325) $PN 1
J 0
(-7288 6337);
DISPLAY 0.787234 (-7288 6337);
PAINT MONO (-7288 6337);
FORCEPROP 1 LASTPIN (-7100 6325) $PN 2
J 0
(-7138 6337);
DISPLAY 0.787234 (-7138 6337);
PAINT MONO (-7138 6337);
FORCEPROP 1 LAST VALUE 1K
J 2
(-6975 6325);
DISPLAY 0.510638 (-6975 6325);
FORCEPROP 1 LAST TOLERANCE 1%
J 0
(-6925 6325);
DISPLAY 0.510638 (-6925 6325);
FORCEPROP 1 LAST MATERIAL CHIP
J 0
(-7325 6425);
DISPLAY 0.510638 (-7325 6425);
FORCEPROP 1 LAST WATTAGE 1/16W
J 2
(-7075 6425);
DISPLAY 0.510638 (-7075 6425);
FORCEPROP 1 LAST PACK_TYPE 0402LF
J 0
(-7050 6425);
DISPLAY 0.510638 (-7050 6425);
FORCEPROP 2 LAST CDS_LIB pure_quanta
J 0
(-7200 6325);
DISPLAY INVISIBLE (-7200 6325);
FORCEPROP 1 LAST PATH I93
J 0
(-7250 6475);
DISPLAY 0.978723 (-7250 6475);
PAINT WHITE (-7250 6475);
DISPLAY INVISIBLE (-7250 6475);
FORCEPROP 1 LAST PART_NUMBER CS21002FB06
J 0
(-7325 6375);
DISPLAY 0.510638 (-7325 6375);
DISPLAY INVISIBLE (-7325 6375);
FORCEADD VCC15..1
(-7575 6450);
FORCEPROP 3 LASTPIN (-7575 6400) SIG_NAME P1V8_AUX\g
J 0
(-7565 6410);
DISPLAY 0.659574 (-7565 6410);
PAINT MONO (-7565 6410);
DISPLAY INVISIBLE (-7565 6410);
FORCEPROP 1 LAST HDL_POWER P1V8_AUX
J 1
(-7575 6500);
DISPLAY 0.617021 (-7575 6500);
PAINT GREEN (-7575 6500);
FORCEPROP 2 LAST CDS_LIB pure_quanta_power
J 0
(-7575 6450);
DISPLAY INVISIBLE (-7575 6450);
FORCEPROP 1 LAST PATH I94
J 0
(-7525 6475);
DISPLAY 0.872340 (-7525 6475);
PAINT AQUA (-7525 6475);
DISPLAY INVISIBLE (-7525 6475);
FORCEADD Q_SHORT..1
(-7750 4175);
FORCEPROP 1 LAST LOCATION PJ09_P1_P
J 0
(-7825 4230);
DISPLAY 0.723404 (-7825 4230);
PAINT GREEN (-7825 4230);
FORCEPROP 0 LAST $SEC 1
J 0
(-7825 4425);
DISPLAY 0.680851 (-7825 4425);
PAINT MONO (-7825 4425);
DISPLAY INVISIBLE (-7825 4425);
FORCEPROP 0 LAST CDS_SEC 1
J 0
(-7825 4425);
DISPLAY 0.680851 (-7825 4425);
DISPLAY INVISIBLE (-7825 4425);
FORCEPROP 0 LASTPIN (-7875 4175) $PN 1
J 2
(-7885 4185);
DISPLAY 0.680851 (-7885 4185);
PAINT MONO (-7885 4185);
FORCEPROP 0 LASTPIN (-7625 4175) $PN 2
J 0
(-7615 4185);
DISPLAY 0.680851 (-7615 4185);
PAINT MONO (-7615 4185);
FORCEPROP 1 LAST MATERIAL EMPTY
J 0
(-7825 4335);
DISPLAY 0.723404 (-7825 4335);
PAINT GREEN (-7825 4335);
FORCEPROP 2 LAST PACK_TYPE SM
J 0
(-7825 4375);
DISPLAY 0.680851 (-7825 4375);
FORCEPROP 1 LAST NEEDS_NO_SIZE TRUE
J 0
(-7750 4175);
DISPLAY 0.468085 (-7750 4175);
PAINT GREEN (-7750 4175);
DISPLAY INVISIBLE (-7750 4175);
FORCEPROP 2 LAST CDS_LIB pure_quanta
J 0
(-7750 4175);
DISPLAY INVISIBLE (-7750 4175);
FORCEPROP 1 LAST PATH I95
J 0
(-7825 4380);
DISPLAY 0.723404 (-7825 4380);
PAINT GREEN (-7825 4380);
DISPLAY INVISIBLE (-7825 4380);
FORCEPROP 1 LAST PART_NUMBER SHORT16
J 0
(-7825 4285);
DISPLAY 0.723404 (-7825 4285);
PAINT GREEN (-7825 4285);
DISPLAY INVISIBLE (-7825 4285);
FORCEADD Q_SHORT..1
(-7750 3800);
FORCEPROP 1 LAST LOCATION PJ09_P1_N
J 0
(-7825 3855);
DISPLAY 0.723404 (-7825 3855);
PAINT GREEN (-7825 3855);
FORCEPROP 0 LAST $SEC 1
J 0
(-7825 4050);
DISPLAY 0.680851 (-7825 4050);
PAINT MONO (-7825 4050);
DISPLAY INVISIBLE (-7825 4050);
FORCEPROP 0 LAST CDS_SEC 1
J 0
(-7825 4050);
DISPLAY 0.680851 (-7825 4050);
DISPLAY INVISIBLE (-7825 4050);
FORCEPROP 0 LASTPIN (-7875 3800) $PN 1
J 2
(-7885 3810);
DISPLAY 0.680851 (-7885 3810);
PAINT MONO (-7885 3810);
FORCEPROP 0 LASTPIN (-7625 3800) $PN 2
J 0
(-7615 3810);
DISPLAY 0.680851 (-7615 3810);
PAINT MONO (-7615 3810);
FORCEPROP 1 LAST MATERIAL EMPTY
J 0
(-7825 3960);
DISPLAY 0.723404 (-7825 3960);
PAINT GREEN (-7825 3960);
FORCEPROP 2 LAST PACK_TYPE SM
J 0
(-7825 4000);
DISPLAY 0.680851 (-7825 4000);
FORCEPROP 1 LAST NEEDS_NO_SIZE TRUE
J 0
(-7750 3800);
DISPLAY 0.468085 (-7750 3800);
PAINT GREEN (-7750 3800);
DISPLAY INVISIBLE (-7750 3800);
FORCEPROP 2 LAST CDS_LIB pure_quanta
J 0
(-7750 3800);
DISPLAY INVISIBLE (-7750 3800);
FORCEPROP 1 LAST PATH I96
J 0
(-7825 4005);
DISPLAY 0.723404 (-7825 4005);
PAINT GREEN (-7825 4005);
DISPLAY INVISIBLE (-7825 4005);
FORCEPROP 1 LAST PART_NUMBER SHORT16
J 0
(-7825 3910);
DISPLAY 0.723404 (-7825 3910);
PAINT GREEN (-7825 3910);
DISPLAY INVISIBLE (-7825 3910);
FORCEADD DNS..2
(-6325 6375);
PAINT RED (-6325 6375);
FORCEPROP 2 LAST CDS_LIB mstr_misc
J 0
(-6325 6375);
DISPLAY INVISIBLE (-6325 6375);
FORCEPROP 1 LAST COMMENT_BODY TRUE
R 1
J 0
(-6250 6150);
DISPLAY 0.872340 (-6250 6150);
PAINT GREEN (-6250 6150);
DISPLAY INVISIBLE (-6250 6150);
FORCEADD DNS..2
(-6450 4750);
PAINT RED (-6450 4750);
FORCEPROP 2 LAST CDS_LIB mstr_misc
J 0
(-6450 4750);
DISPLAY INVISIBLE (-6450 4750);
FORCEPROP 1 LAST COMMENT_BODY TRUE
R 1
J 0
(-6375 4525);
DISPLAY 0.872340 (-6375 4525);
PAINT GREEN (-6375 4525);
DISPLAY INVISIBLE (-6375 4525);
FORCEADD DNS..2
(-5250 375);
PAINT RED (-5250 375);
FORCEPROP 2 LAST CDS_LIB mstr_misc
J 0
(-5250 375);
DISPLAY INVISIBLE (-5250 375);
FORCEPROP 1 LAST COMMENT_BODY TRUE
R 1
J 0
(-5175 150);
DISPLAY 0.872340 (-5175 150);
PAINT GREEN (-5175 150);
DISPLAY INVISIBLE (-5175 150);
FORCEADD DNS..2
(-5475 5275);
PAINT RED (-5475 5275);
FORCEPROP 2 LAST CDS_LIB mstr_misc
J 0
(-5475 5275);
DISPLAY INVISIBLE (-5475 5275);
FORCEPROP 1 LAST COMMENT_BODY TRUE
R 1
J 0
(-5400 5050);
DISPLAY 0.872340 (-5400 5050);
PAINT GREEN (-5400 5050);
DISPLAY INVISIBLE (-5400 5050);
FORCEADD DNS..2
(-6550 5750);
PAINT RED (-6550 5750);
FORCEPROP 2 LAST CDS_LIB mstr_misc
J 0
(-6550 5750);
DISPLAY INVISIBLE (-6550 5750);
FORCEPROP 1 LAST COMMENT_BODY TRUE
R 1
J 0
(-6475 5525);
DISPLAY 0.872340 (-6475 5525);
PAINT GREEN (-6475 5525);
DISPLAY INVISIBLE (-6475 5525);
FORCEADD DNS..2
(-6550 5600);
PAINT RED (-6550 5600);
FORCEPROP 2 LAST CDS_LIB mstr_misc
J 0
(-6550 5600);
DISPLAY INVISIBLE (-6550 5600);
FORCEPROP 1 LAST COMMENT_BODY TRUE
R 1
J 0
(-6475 5375);
DISPLAY 0.872340 (-6475 5375);
PAINT GREEN (-6475 5375);
DISPLAY INVISIBLE (-6475 5375);
FORCEADD DNS..2
(-6550 5425);
PAINT RED (-6550 5425);
FORCEPROP 2 LAST CDS_LIB mstr_misc
J 0
(-6550 5425);
DISPLAY INVISIBLE (-6550 5425);
FORCEPROP 1 LAST COMMENT_BODY TRUE
R 1
J 0
(-6475 5200);
DISPLAY 0.872340 (-6475 5200);
PAINT GREEN (-6475 5200);
DISPLAY INVISIBLE (-6475 5200);
FORCEADD DNS..2
(-6700 575);
PAINT RED (-6700 575);
FORCEPROP 2 LAST CDS_LIB mstr_misc
J 0
(-6700 575);
DISPLAY INVISIBLE (-6700 575);
FORCEPROP 1 LAST COMMENT_BODY TRUE
R 1
J 0
(-6625 350);
DISPLAY 0.872340 (-6625 350);
PAINT GREEN (-6625 350);
DISPLAY INVISIBLE (-6625 350);
FORCEADD DNS..2
(-6275 850);
PAINT RED (-6275 850);
FORCEPROP 2 LAST CDS_LIB mstr_misc
J 0
(-6275 850);
DISPLAY INVISIBLE (-6275 850);
FORCEPROP 1 LAST COMMENT_BODY TRUE
R 1
J 0
(-6200 625);
DISPLAY 0.872340 (-6200 625);
PAINT GREEN (-6200 625);
DISPLAY INVISIBLE (-6200 625);
FORCEADD DNS..2
(-5650 6350);
PAINT RED (-5650 6350);
FORCEPROP 2 LAST CDS_LIB mstr_misc
J 0
(-5650 6350);
DISPLAY INVISIBLE (-5650 6350);
FORCEPROP 1 LAST COMMENT_BODY TRUE
R 1
J 0
(-5575 6125);
DISPLAY 0.872340 (-5575 6125);
PAINT GREEN (-5575 6125);
DISPLAY INVISIBLE (-5575 6125);
FORCEADD DNS..2
(-5850 400);
PAINT RED (-5850 400);
FORCEPROP 2 LAST CDS_LIB mstr_misc
J 0
(-5850 400);
DISPLAY INVISIBLE (-5850 400);
FORCEPROP 1 LAST COMMENT_BODY TRUE
R 1
J 0
(-5775 175);
DISPLAY 0.872340 (-5775 175);
PAINT GREEN (-5775 175);
DISPLAY INVISIBLE (-5775 175);
FORCEADD DNS..2
(-1800 750);
PAINT RED (-1800 750);
FORCEPROP 2 LAST CDS_LIB mstr_misc
J 0
(-1800 750);
DISPLAY INVISIBLE (-1800 750);
FORCEPROP 1 LAST COMMENT_BODY TRUE
R 1
J 0
(-1725 525);
DISPLAY 0.872340 (-1725 525);
PAINT GREEN (-1725 525);
DISPLAY INVISIBLE (-1725 525);
FORCEADD QUANTA_TITLE_BLOCK_C..1
(300 -100);
FORCEPROP 0 LAST CDS_CON_LAST_MODIFIED Thu Sep 14 16:13:02 2023
J 0
(-1585 -85);
DISPLAY INVISIBLE (-1585 -85);
FORCEPROP 1 LAST CUSTOM_TXT_CDS <CON_LAST_MODIFIED>
J 0
(-1585 -85);
DISPLAY 0.978723 (-1585 -85);
FORCEPROP 2 LAST CUSTOM_TXT_CDS <XR_PAGE_TITLE>
J 0
(-7590 5150);
DISPLAY 0.638298 (-7590 5150);
PAINT PINK (-7590 5150);
DISPLAY INVISIBLE (-7590 5150);
FORCEPROP 1 LAST CUSTOM_TXT_CDS <NAME_2>
J 0
(-2875 -50);
FORCEPROP 1 LAST CUSTOM_TXT_CDS <NAME_1>
J 0
(-2875 75);
FORCEPROP 1 LAST CUSTOM_TXT_CDS <Q_NUMBER>
J 0
(-1103 3);
DISPLAY 1.212766 (-1103 3);
FORCEPROP 1 LAST CUSTOM_TXT_CDS <Q_PROJ>
J 0
(-2082 2);
DISPLAY 1.212766 (-2082 2);
FORCEPROP 1 LAST CUSTOM_TXT_CDS <Q_REV>
J 0
(116 3);
DISPLAY 1.212766 (116 3);
FORCEPROP 1 LAST CUSTOM_TXT_CDS <CON_PAGE_NUM> OF <CON_TOTAL_PAGES>
J 0
(-146 -82);
DISPLAY 0.978723 (-146 -82);
FORCEPROP 1 LAST Q_TITLE P0V9_CPU1_RT_2D_VR_CONTROLLER
J 0
(-9000 -50);
DISPLAY 2.446809 (-9000 -50);
PAINT GREEN (-9000 -50);
FORCEPROP 2 LAST PAGE_BORDER TRUE
J 0
(-7590 5150);
DISPLAY 0.638298 (-7590 5150);
PAINT PINK (-7590 5150);
DISPLAY INVISIBLE (-7590 5150);
FORCEPROP 1 LAST CDS_LMAN_SYM_OUTLINE -9475,6775,100,-125
J 0
(300 -100);
DISPLAY 0.468085 (300 -100);
PAINT GREEN (300 -100);
DISPLAY INVISIBLE (300 -100);
FORCEPROP 2 LAST CDS_LIB pure_quanta
J 0
(300 -100);
DISPLAY INVISIBLE (300 -100);
FORCEPROP 2 LAST CDS_XR_PAGE_TITLE CR-365 : @T6G_MB_LIB.T6G(SCH_1):PAGE365
J 0
(-7590 5150);
DISPLAY 0.638298 (-7590 5150);
PAINT PINK (-7590 5150);
DISPLAY INVISIBLE (-7590 5150);
FORCEPROP 1 LAST Q_DEPT BU9
J 1
(-3463 -51);
DISPLAY 1.957447 (-3463 -51);
PAINT GREEN (-3463 -51);
DISPLAY INVISIBLE (-3463 -51);
FORCEPROP 1 LAST COMMENT_BODY TRUE
J 0
(312 -113);
DISPLAY 0.978723 (312 -113);
PAINT GREEN (312 -113);
DISPLAY INVISIBLE (312 -113);
WIRE 16 -1 (-7450 1775)(-7825 1775);
WIRE 16 -1 (-6100 1075)(-5850 1075);
WIRE 16 -1 (-6100 1075)(-6100 1025);
WIRE 16 -1 (-7875 3800)(-8050 3800);
WIRE 16 -1 (-8050 3800)(-8050 3600);
WIRE 16 -1 (-6650 3650)(-6650 3600);
WIRE 16 -1 (-6650 3650)(-7075 3650);
WIRE 16 -1 (-6650 6325)(-6650 6400);
WIRE 16 -1 (-6650 6325)(-6425 6325);
WIRE 16 -1 (-2500 600)(-2500 675);
WIRE 16 -1 (-1800 575)(-1800 675);
WIRE 16 -1 (-2025 1275)(-1750 1275);
WIRE 16 -1 (-1750 1275)(-1750 1200);
WIRE 16 -1 (-2025 1925)(-1750 1925);
WIRE 16 -1 (-1750 1925)(-1750 1825);
WIRE 16 -1 (-2025 2375)(-1750 2375);
WIRE 16 -1 (-1750 2375)(-1750 2200);
WIRE 16 -1 (-4800 3025)(-5000 3025);
WIRE 16 -1 (-5000 3025)(-5000 2925);
WIRE 16 -1 (-5550 6325)(-5000 6325);
WIRE 16 -1 (-2025 2825)(-1750 2825);
WIRE 16 -1 (-1750 2825)(-1750 2625);
WIRE 16 -1 (-2025 3275)(-1750 3275);
WIRE 16 -1 (-1750 3275)(-1750 3075);
WIRE 16 -1 (-2025 3725)(-1750 3725);
WIRE 16 -1 (-1750 3725)(-1750 3575);
WIRE 16 -1 (-2025 4175)(-1750 4175);
WIRE 16 -1 (-1750 4175)(-1750 4075);
WIRE 16 -1 (-750 2075)(-750 2000);
WIRE 16 -1 (-7575 5650)(-7575 5500);
WIRE 16 -1 (-7075 5725)(-6675 5725);
WIRE 16 -1 (-7075 5800)(-7075 5725);
WIRE 16 -1 (-7075 5725)(-7075 5575);
WIRE 16 -1 (-7075 5575)(-6675 5575);
WIRE 16 -1 (-7075 5575)(-7075 5425);
WIRE 16 -1 (-6675 5425)(-7075 5425);
WIRE 16 -1 (-7075 4725)(-7075 5425);
WIRE 16 -1 (-6575 4725)(-7075 4725);
WIRE 16 -1 (-2875 5400)(-2875 5300);
WIRE 16 -1 (-2875 5300)(-2475 5300);
WIRE 16 -1 (-2075 5300)(-2475 5300);
WIRE 16 -1 (-2475 5300)(-2475 5400);
WIRE 16 -1 (-3450 4625)(-2225 4625);
FORCEPROP 2 LAST SIG_NAME P0V9_RETIMER_CPU1_IMON2
J 0
(-3310 4635);
DISPLAY 0.617021 (-3310 4635);
WIRE 17 273 (-8875 600)(-7650 600);
WIRE 17 273 (-8875 600)(-8875 175);
WIRE 17 273 (-7650 600)(-7650 175);
WIRE 17 273 (-8875 175)(-7650 175);
WIRE 16 -1 (-7250 1775)(-4800 1775);
FORCEPROP 2 LAST SIG_NAME P0V9_RETIMER_CPU1_EN1_R
J 0
(-5860 1785);
DISPLAY 0.808511 (-5860 1785);
FORCEPROP 2 LASTPROP $XRERR UNIQUE?
J 0
(-6100 1785);
DISPLAY 0.638298 (-6100 1785);
PAINT MONO (-6100 1785);
DISPLAY INVISIBLE (-6100 1785);
WIRE 16 -1 (-6300 2275)(-6300 1925);
WIRE 16 -1 (-4800 1925)(-6300 1925);
FORCEPROP 2 LAST SIG_NAME P0V9_RETIMER_CPU1_INALERT
J 0
(-5735 1935);
DISPLAY 0.638298 (-5735 1935);
FORCEPROP 2 LASTPROP $XRERR UNIQUE?
J 0
(-5975 1935);
DISPLAY 0.638298 (-5975 1935);
PAINT MONO (-5975 1935);
DISPLAY INVISIBLE (-5975 1935);
WIRE 16 -1 (-3450 3275)(-2225 3275);
FORCEPROP 2 LAST SIG_NAME NC_P0V9_RETIMER_CPU1_IMON5
J 0
(-3310 3285);
DISPLAY 0.617021 (-3310 3285);
FORCEPROP 2 LASTPROP $XRERR UNIQUE?
J 0
(-3550 3285);
DISPLAY 0.638298 (-3550 3285);
PAINT MONO (-3550 3285);
DISPLAY INVISIBLE (-3550 3285);
WIRE 16 -1 (-3450 3725)(-2225 3725);
FORCEPROP 2 LAST SIG_NAME NC_P0V9_RETIMER_CPU1_IMON4
J 0
(-3310 3735);
DISPLAY 0.617021 (-3310 3735);
FORCEPROP 2 LASTPROP $XRERR UNIQUE?
J 0
(-3550 3735);
DISPLAY 0.638298 (-3550 3735);
PAINT MONO (-3550 3735);
DISPLAY INVISIBLE (-3550 3735);
WIRE 16 -1 (-3450 4275)(-2225 4275);
FORCEPROP 2 LAST SIG_NAME NC_P0V9_RETIMER_CPU1_PWM3
J 0
(-3310 4285);
DISPLAY 0.617021 (-3310 4285);
FORCEPROP 2 LASTPROP $XRERR UNIQUE?
J 0
(-2220 4275);
DISPLAY 0.638298 (-2220 4275);
PAINT MONO (-2220 4275);
DISPLAY INVISIBLE (-2220 4275);
WIRE 16 -1 (-3450 5175)(-2225 5175);
FORCEPROP 2 LAST SIG_NAME P0V9_RETIMER_CPU1_PWM1
J 0
(-3310 5185);
DISPLAY 0.617021 (-3310 5185);
WIRE 16 -1 (-7575 6325)(-7300 6325);
WIRE 16 -1 (-7575 6400)(-7575 6325);
WIRE 16 -1 (-1675 6250)(-1675 6175);
WIRE 16 -1 (-1675 6175)(-2050 6175);
WIRE 16 -1 (-2875 5875)(-2875 5775);
WIRE 16 -1 (-2875 5775)(-2475 5775);
WIRE 16 -1 (-2075 5775)(-2475 5775);
WIRE 16 -1 (-2475 5875)(-2475 5775);
WIRE 16 -1 (-6700 725)(-6400 725);
WIRE 16 -1 (-6700 825)(-6700 725);
WIRE 16 -1 (-6700 825)(-6400 825);
WIRE 16 -1 (-6700 900)(-6700 825);
WIRE 16 -1 (-4800 2775)(-5000 2775);
WIRE 16 -1 (-5000 2700)(-5000 2775);
WIRE 16 -1 (-7000 600)(-6800 600);
WIRE 16 -1 (-7000 700)(-7000 600);
WIRE 16 -1 (-4800 625)(-4900 625);
WIRE 16 -1 (-4900 550)(-4900 625);
WIRE 16 -1 (-5250 300)(-5250 200);
WIRE 16 -1 (-5250 200)(-5125 200);
WIRE 16 -1 (-5125 300)(-5125 200);
WIRE 16 -1 (-5125 200)(-5125 150);
WIRE 16 -1 (-5500 5150)(-5500 5100);
WIRE 16 -1 (-5500 5100)(-5850 5100);
WIRE 16 -1 (-5850 5150)(-5850 5100);
WIRE 16 -1 (-5850 5100)(-6200 5100);
WIRE 16 -1 (-6200 5150)(-6200 5100);
WIRE 16 -1 (-6200 5100)(-6300 5100);
WIRE 16 -1 (-6000 300)(-6000 200);
WIRE 16 -1 (-6000 200)(-5875 200);
WIRE 16 -1 (-5875 200)(-5875 300);
WIRE 16 -1 (-5875 150)(-5875 200);
WIRE 16 -1 (-5925 2475)(-5925 2525);
WIRE 16 -1 (-5925 2525)(-6300 2525);
WIRE 16 -1 (-6300 2525)(-6300 2475);
WIRE 16 -1 (-6300 2550)(-6300 2525);
WIRE 16 -1 (-6625 4425)(-6625 4325);
WIRE 16 -1 (-6625 4325)(-7025 4325);
WIRE 16 -1 (-8050 4175)(-7875 4175);
WIRE 16 -1 (-8050 4425)(-8050 4175);
WIRE 2 2175 (250 6400)(250 5600);
WIRE 2 2175 (-1325 6400)(250 6400);
WIRE 2 2175 (250 5600)(-1325 5600);
WIRE 2 2175 (-1325 5600)(-1325 6400);
WIRE 16 -1 (-3450 5075)(-2225 5075);
FORCEPROP 2 LAST SIG_NAME P0V9_RETIMER_CPU1_IMON1
J 0
(-3310 5085);
DISPLAY 0.617021 (-3310 5085);
WIRE 16 -1 (-4800 4875)(-6400 4875);
FORCEPROP 2 LAST SIG_NAME P0V9_RETIMER_CPU1_PMSDA_R
J 0
(-5685 4885);
DISPLAY 0.617021 (-5685 4885);
FORCEPROP 2 LASTPROP $XRERR UNIQUE?
J 0
(-5925 4885);
DISPLAY 0.638298 (-5925 4885);
PAINT MONO (-5925 4885);
DISPLAY INVISIBLE (-5925 4885);
WIRE 16 -1 (-4800 4725)(-6375 4725);
FORCEPROP 2 LAST SIG_NAME TP_P0V9_RETIMER_CPU1_PMALERT
J 0
(-5760 4735);
DISPLAY 0.617021 (-5760 4735);
FORCEPROP 2 LASTPROP $XRERR UNIQUE?
J 0
(-6000 4735);
DISPLAY 0.638298 (-6000 4735);
PAINT MONO (-6000 4735);
DISPLAY INVISIBLE (-6000 4735);
WIRE 16 -1 (-2475 6075)(-2475 6175);
WIRE 16 -1 (-2250 6175)(-2475 6175);
WIRE 16 -1 (-2875 6175)(-2475 6175);
WIRE 16 -1 (-3450 6175)(-2875 6175);
FORCEPROP 2 LAST SIG_NAME P0V9_RETIMER_CPU1_VCC
J 0
(-3310 6185);
DISPLAY 0.617021 (-3310 6185);
FORCEPROP 2 LASTPROP $XRERR UNIQUE?
J 0
(-3550 6185);
DISPLAY 0.638298 (-3550 6185);
PAINT MONO (-3550 6185);
DISPLAY INVISIBLE (-3550 6185);
WIRE 16 -1 (-2875 6075)(-2875 6175);
WIRE 16 -1 (-4800 5025)(-6400 5025);
FORCEPROP 2 LAST SIG_NAME P0V9_RETIMER_CPU1_PMSCL_R
J 0
(-5685 5035);
DISPLAY 0.617021 (-5685 5035);
FORCEPROP 2 LASTPROP $XRERR UNIQUE?
J 0
(-5925 5035);
DISPLAY 0.638298 (-5925 5035);
PAINT MONO (-5925 5035);
DISPLAY INVISIBLE (-5925 5035);
WIRE 16 -1 (-5850 5350)(-5850 5575);
WIRE 16 -1 (-5850 5575)(-4800 5575);
WIRE 16 -1 (-6475 5575)(-5850 5575);
FORCEPROP 2 LAST SIG_NAME P0V9_RETIMER_CPU1_SVID_SDA
J 0
(-5910 5585);
DISPLAY 0.808511 (-5910 5585);
FORCEPROP 2 LASTPROP $XRERR UNIQUE?
J 0
(-6150 5585);
DISPLAY 0.638298 (-6150 5585);
PAINT MONO (-6150 5585);
DISPLAY INVISIBLE (-6150 5585);
WIRE 16 -1 (-4800 5425)(-5500 5425);
WIRE 16 -1 (-5500 5350)(-5500 5425);
WIRE 16 -1 (-5500 5425)(-6475 5425);
FORCEPROP 2 LAST SIG_NAME TP_P0V9_RETIMER_CPU1_SVID_ALERT_N
J 0
(-6185 5435);
DISPLAY 0.808511 (-6185 5435);
FORCEPROP 2 LASTPROP $XRERR UNIQUE?
J 0
(-6425 5435);
DISPLAY 0.638298 (-6425 5435);
PAINT MONO (-6425 5435);
DISPLAY INVISIBLE (-6425 5435);
WIRE 16 -1 (-2075 1675)(-3450 1675);
FORCEPROP 2 LAST SIG_NAME P0V9_RETIMER_CPU1_VRHOT
J 0
(-3310 1685);
DISPLAY 0.638298 (-3310 1685);
FORCEPROP 2 LASTPROP $XRERR UNIQUE?
J 0
(-3550 1685);
DISPLAY 0.638298 (-3550 1685);
PAINT MONO (-3550 1685);
DISPLAY INVISIBLE (-3550 1685);
WIRE 16 -1 (-3450 4175)(-2225 4175);
FORCEPROP 2 LAST SIG_NAME NC_P0V9_RETIMER_CPU1_IMON3
J 0
(-3310 4185);
DISPLAY 0.617021 (-3310 4185);
FORCEPROP 2 LASTPROP $XRERR UNIQUE?
J 0
(-3550 4185);
DISPLAY 0.638298 (-3550 4185);
PAINT MONO (-3550 4185);
DISPLAY INVISIBLE (-3550 4185);
WIRE 16 -1 (-4800 1375)(-5900 1375);
FORCEPROP 2 LAST SIG_NAME NC_P0V9_RETIMER_CPU1_PG1
J 0
(-5710 1385);
DISPLAY 0.617021 (-5710 1385);
FORCEPROP 2 LASTPROP $XRERR UNIQUE?
J 0
(-6140 1375);
DISPLAY 0.638298 (-6140 1375);
PAINT MONO (-6140 1375);
DISPLAY INVISIBLE (-6140 1375);
WIRE 16 -1 (-6200 5350)(-6200 5725);
WIRE 16 -1 (-4800 5725)(-6200 5725);
FORCEPROP 2 LAST SIG_NAME P0V9_RETIMER_CPU1_SVID_CLK
J 0
(-5910 5735);
DISPLAY 0.808511 (-5910 5735);
FORCEPROP 2 LASTPROP $XRERR UNIQUE?
J 0
(-6150 5735);
DISPLAY 0.638298 (-6150 5735);
PAINT MONO (-6150 5735);
DISPLAY INVISIBLE (-6150 5735);
WIRE 16 -1 (-6200 5725)(-6475 5725);
WIRE 16 -1 (-6050 6025)(-6050 5975);
WIRE 16 -1 (-6050 6025)(-4800 6025);
FORCEPROP 2 LAST SIG_NAME P0V9_RETIMER_CPU1_EN0_R
J 0
(-5785 6035);
DISPLAY 0.808511 (-5785 6035);
FORCEPROP 2 LASTPROP $XRERR UNIQUE?
J 0
(-6025 6035);
DISPLAY 0.638298 (-6025 6035);
PAINT MONO (-6025 6035);
DISPLAY INVISIBLE (-6025 6035);
WIRE 16 -1 (-6400 6025)(-6050 6025);
WIRE 16 -1 (-6050 5975)(-7575 5975);
WIRE 16 -1 (-7575 5975)(-7575 5850);
WIRE 16 -1 (-4800 3875)(-5000 3875);
WIRE 16 -1 (-5000 3800)(-5000 3875);
WIRE 16 -1 (-5000 3800)(-5650 3800);
WIRE 16 -1 (-5650 3900)(-5650 3800);
WIRE 16 -1 (-7450 3800)(-5650 3800);
FORCEPROP 2 LAST SIG_NAME P0V9_RETIMER_CPU1_SENSE_SH_N
J 0
(-7285 3810);
DISPLAY 0.617021 (-7285 3810);
FORCEPROP 2 LASTPROP $XRERR UNIQUE?
J 0
(-7525 3810);
DISPLAY 0.638298 (-7525 3810);
PAINT MONO (-7525 3810);
DISPLAY INVISIBLE (-7525 3810);
WIRE 16 -1 (-7450 3800)(-7625 3800);
WIRE 16 -1 (-7450 3650)(-7450 3800);
WIRE 16 -1 (-7450 3650)(-7275 3650);
WIRE 16 -1 (-3450 3825)(-2225 3825);
FORCEPROP 2 LAST SIG_NAME NC_P0V9_RETIMER_CPU1_PWM4
J 0
(-3310 3835);
DISPLAY 0.617021 (-3310 3835);
FORCEPROP 2 LASTPROP $XRERR UNIQUE?
J 0
(-2220 3825);
DISPLAY 0.638298 (-2220 3825);
PAINT MONO (-2220 3825);
DISPLAY INVISIBLE (-2220 3825);
WIRE 16 -1 (-6000 4175)(-5650 4175);
WIRE 16 -1 (-5000 4175)(-5650 4175);
FORCEPROP 2 LAST SIG_NAME P0V9_RETIMER_CPU1_SENSE_R_P
J 0
(-5760 4185);
DISPLAY 0.617021 (-5760 4185);
FORCEPROP 2 LASTPROP $XRERR UNIQUE?
J 0
(-6000 4185);
DISPLAY 0.638298 (-6000 4185);
PAINT MONO (-6000 4185);
DISPLAY INVISIBLE (-6000 4185);
WIRE 16 -1 (-5650 4100)(-5650 4175);
WIRE 16 -1 (-5000 4175)(-5000 4125);
WIRE 16 -1 (-5000 4125)(-4800 4125);
WIRE 16 -1 (-3450 2475)(-2225 2475);
FORCEPROP 2 LAST SIG_NAME NC_P0V9_RETIMER_CPU1_PWM7
J 0
(-3310 2485);
DISPLAY 0.617021 (-3310 2485);
FORCEPROP 2 LASTPROP $XRERR UNIQUE?
J 0
(-2220 2475);
DISPLAY 0.638298 (-2220 2475);
PAINT MONO (-2220 2475);
DISPLAY INVISIBLE (-2220 2475);
WIRE 16 -1 (-7100 6325)(-6725 6325);
WIRE 16 -1 (-6725 6325)(-6725 6175);
WIRE 16 -1 (-5975 6175)(-6725 6175);
WIRE 16 -1 (-7125 6175)(-6725 6175);
WIRE 16 -1 (-5975 6175)(-4800 6175);
FORCEPROP 2 LAST SIG_NAME PWRGD_P0V9_RETIMER_CPU1_R
J 0
(-5810 6185);
DISPLAY 0.765957 (-5810 6185);
FORCEPROP 2 LASTPROP $XRERR UNIQUE?
J 0
(-6050 6185);
DISPLAY 0.638298 (-6050 6185);
PAINT MONO (-6050 6185);
DISPLAY INVISIBLE (-6050 6185);
WIRE 16 -1 (-5975 6175)(-5975 6325);
WIRE 16 -1 (-5750 6325)(-5975 6325);
WIRE 16 -1 (-5975 6325)(-6225 6325);
WIRE 16 -1 (-3450 4725)(-2225 4725);
FORCEPROP 2 LAST SIG_NAME P0V9_RETIMER_CPU1_PWM2
J 0
(-3310 4735);
DISPLAY 0.617021 (-3310 4735);
WIRE 16 -1 (-3450 5875)(-3350 5875);
WIRE 16 -1 (-3350 5875)(-3350 5700);
WIRE 16 -1 (-2875 5700)(-3350 5700);
FORCEPROP 2 LAST SIG_NAME PV09_RETIMER_CPU1_VCCS
J 0
(-3285 5710);
DISPLAY 0.617021 (-3285 5710);
WIRE 16 -1 (-2475 5700)(-2875 5700);
WIRE 16 -1 (-2875 5600)(-2875 5700);
WIRE 16 -1 (-2075 5700)(-2475 5700);
WIRE 16 -1 (-2475 5600)(-2475 5700);
WIRE 16 -1 (-6150 825)(-6000 825);
WIRE 16 -1 (-6200 825)(-6150 825);
WIRE 16 -1 (-6150 825)(-6150 600);
WIRE 16 -1 (-6000 825)(-5875 825);
WIRE 16 -1 (-6000 500)(-6000 825);
WIRE 16 -1 (-4800 825)(-5875 825);
FORCEPROP 2 LAST SIG_NAME P0V9_RETIMER_CPU1_VMON
J 0
(-5660 835);
DISPLAY 0.617021 (-5660 835);
FORCEPROP 2 LASTPROP $XRERR UNIQUE?
J 0
(-5900 835);
DISPLAY 0.638298 (-5900 835);
PAINT MONO (-5900 835);
DISPLAY INVISIBLE (-5900 835);
WIRE 16 -1 (-5875 500)(-5875 825);
WIRE 16 -1 (-6150 600)(-6600 600);
WIRE 16 -1 (-5125 500)(-5125 725);
WIRE 16 -1 (-4800 725)(-5125 725);
WIRE 16 -1 (-5125 725)(-5250 725);
WIRE 16 -1 (-5250 500)(-5250 725);
WIRE 16 -1 (-6200 725)(-5250 725);
FORCEPROP 2 LAST SIG_NAME P0V9_RETIMER_CPU1_VINSEN
J 0
(-5710 735);
DISPLAY 0.617021 (-5710 735);
FORCEPROP 2 LASTPROP $XRERR UNIQUE?
J 0
(-5950 735);
DISPLAY 0.638298 (-5950 735);
PAINT MONO (-5950 735);
DISPLAY INVISIBLE (-5950 735);
WIRE 16 -1 (-3450 1275)(-2225 1275);
FORCEPROP 2 LAST SIG_NAME P0V9_RETIMER_CPU1_TEMP1_R
J 0
(-3310 1285);
DISPLAY 0.638298 (-3310 1285);
FORCEPROP 2 LASTPROP $XRERR UNIQUE?
J 0
(-3550 1285);
DISPLAY 0.638298 (-3550 1285);
PAINT MONO (-3550 1285);
DISPLAY INVISIBLE (-3550 1285);
WIRE 16 -1 (-3450 2375)(-2225 2375);
FORCEPROP 2 LAST SIG_NAME NC_P0V9_RETIMER_CPU1_IMON7
J 0
(-3310 2385);
DISPLAY 0.617021 (-3310 2385);
FORCEPROP 2 LASTPROP $XRERR UNIQUE?
J 0
(-3550 2385);
DISPLAY 0.638298 (-3550 2385);
PAINT MONO (-3550 2385);
DISPLAY INVISIBLE (-3550 2385);
WIRE 16 -1 (-3450 3375)(-2225 3375);
FORCEPROP 2 LAST SIG_NAME NC_P0V9_RETIMER_CPU1_PWM5
J 0
(-3310 3385);
DISPLAY 0.617021 (-3310 3385);
FORCEPROP 2 LASTPROP $XRERR UNIQUE?
J 0
(-2220 3375);
DISPLAY 0.638298 (-2220 3375);
PAINT MONO (-2220 3375);
DISPLAY INVISIBLE (-2220 3375);
WIRE 16 -1 (-3450 2925)(-2225 2925);
FORCEPROP 2 LAST SIG_NAME NC_P0V9_RETIMER_CPU1_PWM6
J 0
(-3310 2935);
DISPLAY 0.617021 (-3310 2935);
FORCEPROP 2 LASTPROP $XRERR UNIQUE?
J 0
(-2220 2925);
DISPLAY 0.638298 (-2220 2925);
PAINT MONO (-2220 2925);
DISPLAY INVISIBLE (-2220 2925);
WIRE 16 -1 (-3450 2825)(-2225 2825);
FORCEPROP 2 LAST SIG_NAME NC_P0V9_RETIMER_CPU1_IMON6
J 0
(-3310 2835);
DISPLAY 0.617021 (-3310 2835);
FORCEPROP 2 LASTPROP $XRERR UNIQUE?
J 0
(-3550 2835);
DISPLAY 0.638298 (-3550 2835);
PAINT MONO (-3550 2835);
DISPLAY INVISIBLE (-3550 2835);
WIRE 16 -1 (-5925 2275)(-5925 2175);
WIRE 16 -1 (-4800 2175)(-5925 2175);
FORCEPROP 2 LAST SIG_NAME P0V9_RETIMER_CPU1_CFP
J 0
(-5610 2185);
DISPLAY 0.638298 (-5610 2185);
FORCEPROP 2 LASTPROP $XRERR UNIQUE?
J 0
(-5850 2185);
DISPLAY 0.638298 (-5850 2185);
PAINT MONO (-5850 2185);
DISPLAY INVISIBLE (-5850 2185);
WIRE 16 -1 (-4800 1075)(-5650 1075);
WIRE 16 -1 (-1800 875)(-1800 975);
WIRE 16 -1 (-675 975)(-1800 975);
WIRE 16 -1 (-1800 975)(-2500 975);
WIRE 16 -1 (-2500 875)(-2500 975);
WIRE 16 -1 (-3450 975)(-2500 975);
FORCEPROP 2 LAST SIG_NAME P0V9_RETIMER_CPU1_TEMP0
J 0
(-3310 985);
DISPLAY 0.638298 (-3310 985);
WIRE 16 -1 (-3450 2025)(-2225 2025);
FORCEPROP 2 LAST SIG_NAME NC_P0V9_RETIMER_CPU1_PWM8
J 0
(-3310 2035);
DISPLAY 0.617021 (-3310 2035);
FORCEPROP 2 LASTPROP $XRERR UNIQUE?
J 0
(-2220 2025);
DISPLAY 0.638298 (-2220 2025);
PAINT MONO (-2220 2025);
DISPLAY INVISIBLE (-2220 2025);
WIRE 16 -1 (-3450 1925)(-2225 1925);
FORCEPROP 2 LAST SIG_NAME NC_P0V9_RETIMER_CPU1_IMON8
J 0
(-3310 1935);
DISPLAY 0.617021 (-3310 1935);
FORCEPROP 2 LASTPROP $XRERR UNIQUE?
J 0
(-3550 1935);
DISPLAY 0.638298 (-3550 1935);
PAINT MONO (-3550 1935);
DISPLAY INVISIBLE (-3550 1935);
WIRE 16 -1 (-750 1800)(-750 1675);
WIRE 16 -1 (-1875 1675)(-750 1675);
FORCEPROP 2 LAST SIG_NAME TP_P0V9_RETIMER_CPU1_VRHOT
J 0
(-1560 1685);
DISPLAY 0.638298 (-1560 1685);
FORCEPROP 2 LASTPROP $XRERR UNIQUE?
J 0
(-1800 1685);
DISPLAY 0.638298 (-1800 1685);
PAINT MONO (-1800 1685);
DISPLAY INVISIBLE (-1800 1685);
WIRE 16 -1 (-8175 5025)(-6600 5025);
FORCEPROP 2 LAST SIG_NAME P0V9_RETIMER_CPU1_PMSCL
J 0
(-8035 5035);
DISPLAY 0.680851 (-8035 5035);
WIRE 16 -1 (-7800 6025)(-6600 6025);
FORCEPROP 2 LAST SIG_NAME P0V9_RETIMER_CPU1_EN
J 0
(-7710 6035);
DISPLAY 0.808511 (-7710 6035);
WIRE 16 -1 (-8525 6175)(-7325 6175);
FORCEPROP 2 LAST SIG_NAME PWRGD_P0V9_RETIMER_CPU1
J 0
(-8435 6185);
DISPLAY 0.765957 (-8435 6185);
WIRE 16 -1 (-8200 4875)(-6600 4875);
FORCEPROP 2 LAST SIG_NAME P0V9_RETIMER_CPU1_PMSDA
J 0
(-8035 4885);
DISPLAY 0.680851 (-8035 4885);
WIRE 16 -1 (-7450 4325)(-7225 4325);
WIRE 16 -1 (-7450 4325)(-7450 4175);
WIRE 16 -1 (-7450 4175)(-6200 4175);
FORCEPROP 2 LAST SIG_NAME P0V9_RETIMER_CPU1_SENSE_SH_P
J 0
(-7285 4185);
DISPLAY 0.617021 (-7285 4185);
FORCEPROP 2 LASTPROP $XRERR UNIQUE?
J 0
(-7525 4185);
DISPLAY 0.638298 (-7525 4185);
PAINT MONO (-7525 4185);
DISPLAY INVISIBLE (-7525 4185);
WIRE 16 -1 (-7625 4175)(-7450 4175);
DOT 1 (-7450 4175);
DOT 1 (-7450 3800);
DOT 1 (-6725 6175);
DOT 1 (-5250 725);
DOT 1 (-5650 4175);
DOT 1 (-5975 6175);
DOT 1 (-6150 825);
DOT 1 (-6700 825);
DOT 1 (-5850 5100);
DOT 1 (-7075 5725);
DOT 1 (-2475 6175);
DOT 1 (-2475 5775);
DOT 1 (-2875 5700);
DOT 1 (-2475 5300);
DOT 1 (-5125 200);
DOT 1 (-7075 5575);
DOT 1 (-6300 2525);
DOT 1 (-5875 200);
DOT 1 (-6200 5100);
DOT 1 (-5650 3800);
DOT 1 (-5975 6325);
DOT 1 (-6000 825);
DOT 1 (-2475 5700);
DOT 1 (-1800 975);
DOT 1 (-7075 5425);
DOT 1 (-2875 6175);
DOT 1 (-6050 6025);
DOT 1 (-6200 5725);
DOT 1 (-5850 5575);
DOT 1 (-5500 5425);
DOT 1 (-2500 975);
DOT 1 (-5875 825);
DOT 1 (-5125 725);
FORCENOTE
BOM NOTE
(-1625 5250) 0;
DISPLAY LEFT (-1625 5250);
DISPLAY 1.021277 (-1625 5250);
PAINT WHITE (-1625 5250);
FORCENOTE
MAIN SOURCE: RENESAS    BOM
(-1625 5175) 0;
DISPLAY LEFT (-1625 5175);
DISPLAY 1.021277 (-1625 5175);
PAINT WHITE (-1625 5175);
FORCENOTE
PU6510 = TBD / ISL69260IRAZ-T
(-1625 5100) 0;
DISPLAY LEFT (-1625 5100);
DISPLAY 1.021277 (-1625 5100);
PAINT WHITE (-1625 5100);
FORCENOTE
2ND SOURCE: INFENEON    BOM
(-1625 4925) 0;
DISPLAY LEFT (-1625 4925);
DISPLAY 1.021277 (-1625 4925);
PAINT WHITE (-1625 4925);
FORCENOTE
PU6510 = TBD / XDPE15284D-0000
(-1625 4850) 0;
DISPLAY LEFT (-1625 4850);
DISPLAY 1.021277 (-1625 4850);
PAINT WHITE (-1625 4850);
FORCENOTE
/475
(-8025 350) 0;
DISPLAY LEFT (-8025 350);
DISPLAY 0.638298 (-8025 350);
PAINT WHITE (-8025 350);
FORCENOTE
PMBUS ADDRESS AND CONFIG
(-8925 650) 0;
DISPLAY LEFT (-8925 650);
DISPLAY 1.170213 (-8925 650);
PAINT WHITE (-8925 650);
FORCENOTE
CONFIG/R
(-8025 525) 0;
DISPLAY LEFT (-8025 525);
DISPLAY 0.808511 (-8025 525);
PAINT WHITE (-8025 525);
FORCENOTE
0/22.1K
(-8025 425) 0;
DISPLAY LEFT (-8025 425);
DISPLAY 0.638298 (-8025 425);
PAINT WHITE (-8025 425);
FORCENOTE
0X76
(-8375 425) 0;
DISPLAY LEFT (-8375 425);
DISPLAY 0.638298 (-8375 425);
PAINT WHITE (-8375 425);
FORCENOTE
RENESAS
(-8825 425) 0;
DISPLAY LEFT (-8825 425);
DISPLAY 0.638298 (-8825 425);
PAINT WHITE (-8825 425);
FORCENOTE
VR
(-8825 525) 0;
DISPLAY LEFT (-8825 525);
DISPLAY 0.808511 (-8825 525);
PAINT WHITE (-8825 525);
FORCENOTE
ADDRESS(7-BIT)
(-8600 525) 0;
DISPLAY LEFT (-8600 525);
DISPLAY 0.808511 (-8600 525);
PAINT WHITE (-8600 525);
FORCENOTE
0X76
(-8375 350) 0;
DISPLAY LEFT (-8375 350);
DISPLAY 0.638298 (-8375 350);
PAINT WHITE (-8375 350);
FORCENOTE
INFENEON
(-8825 350) 0;
DISPLAY LEFT (-8825 350);
DISPLAY 0.638298 (-8825 350);
PAINT WHITE (-8825 350);
FORCENOTE
PR6601 =CS01002FB07
(-1575 4375) 0;
DISPLAY LEFT (-1575 4375);
DISPLAY 1.021277 (-1575 4375);
PAINT WHITE (-1575 4375);
FORCENOTE
PR885   = CS25362FB02
(-1575 4450) 0;
DISPLAY LEFT (-1575 4450);
DISPLAY 1.021277 (-1575 4450);
PAINT WHITE (-1575 4450);
FORCENOTE
PR6533 = CS14752FB04
(-1575 4525) 0;
DISPLAY LEFT (-1575 4525);
DISPLAY 1.021277 (-1575 4525);
PAINT WHITE (-1575 4525);
FORCENOTE
PR6541,PR6542,PR6543,PR6544,PR6548 = EMPTY
(-1625 4625) 0;
DISPLAY LEFT (-1625 4625);
DISPLAY 0.808511 (-1625 4625);
PAINT WHITE (-1625 4625);
FORCENOTE
R6800,PR6811,PR6820,PR6539,PR6540 = EMPTY
(-1625 4700) 0;
DISPLAY LEFT (-1625 4700);
DISPLAY 0.808511 (-1625 4700);
PAINT WHITE (-1625 4700);
FORCENOTE
PR6804,PR6806,PR6818,PR6821 = CS21002FB06
(-1625 4775) 0;
DISPLAY LEFT (-1625 4775);
DISPLAY 0.808511 (-1625 4775);
PAINT WHITE (-1625 4775);
FORCENOTE
PC6600 = CH12206KB14
(-1575 4300) 0;
DISPLAY LEFT (-1575 4300);
DISPLAY 1.021277 (-1575 4300);
PAINT WHITE (-1575 4300);
FORCENOTE
PC514   = CH3104J1B00
(-1575 4225) 0;
DISPLAY LEFT (-1575 4225);
DISPLAY 1.021277 (-1575 4225);
PAINT WHITE (-1575 4225);
FORCENOTE
PC6546  = CH4106K1B01
(-1575 4075) 0;
DISPLAY LEFT (-1575 4075);
DISPLAY 1.021277 (-1575 4075);
PAINT WHITE (-1575 4075);
FORCENOTE
PC523   = CH11006JB00
(-1575 4150) 0;
DISPLAY LEFT (-1575 4150);
DISPLAY 1.021277 (-1575 4150);
PAINT WHITE (-1575 4150);
FORCENOTE
OVER-CURRENT PROTECTION= 92A
(-1250 5925) 0;
DISPLAY LEFT (-1250 5925);
DISPLAY 1.021277 (-1250 5925);
PAINT PEACH (-1250 5925);
FORCENOTE
MAX CURRENT = 57.6A
(-1250 6000) 0;
DISPLAY LEFT (-1250 6000);
DISPLAY 1.021277 (-1250 6000);
PAINT PEACH (-1250 6000);
FORCENOTE
TRANSIENT TOLERANCE = 90MV
(-1275 6175) 0;
DISPLAY LEFT (-1275 6175);
DISPLAY 1.021277 (-1275 6175);
PAINT PEACH (-1275 6175);
FORCENOTE
OUTPUT RIPPLE & NOISE < 46MV
(-1275 6250) 0;
DISPLAY LEFT (-1275 6250);
DISPLAY 1.021277 (-1275 6250);
PAINT PEACH (-1275 6250);
FORCENOTE
OUTPUT VOLTAGE = 0.86V - 0.945V
(-1275 6325) 0;
DISPLAY LEFT (-1275 6325);
DISPLAY 1.021277 (-1275 6325);
PAINT PEACH (-1275 6325);
FORCENOTE
DESIGN SPECIFICATION
(-1325 6425) 0;
DISPLAY LEFT (-1325 6425);
DISPLAY 1.276596 (-1325 6425);
PAINT PEACH (-1325 6425);
FORCENOTE
CURRENT STEP = 22A
(-1250 5850) 0;
DISPLAY LEFT (-1250 5850);
DISPLAY 1.021277 (-1250 5850);
PAINT PEACH (-1250 5850);
FORCENOTE
SLEW RATE = 2.5A/US
(-1250 5775) 0;
DISPLAY LEFT (-1250 5775);
DISPLAY 1.021277 (-1250 5775);
PAINT PEACH (-1250 5775);
FORCENOTE
EFFICIENCY > 85% @TDC
(-1250 5625) 0;
DISPLAY LEFT (-1250 5625);
DISPLAY 1.021277 (-1250 5625);
PAINT PEACH (-1250 5625);
FORCENOTE
WORK FREQUENCY = 600KHZ
(-1250 5700) 0;
DISPLAY LEFT (-1250 5700);
DISPLAY 1.021277 (-1250 5700);
PAINT PEACH (-1250 5700);
FORCENOTE
TDC = 54.7A
(-1250 6075) 0;
DISPLAY LEFT (-1250 6075);
DISPLAY 1.021277 (-1250 6075);
PAINT PEACH (-1250 6075);
FORCENOTE
REMOTE SENSE
(-8325 4575) 0;
DISPLAY LEFT (-8325 4575);
DISPLAY 1.021277 (-8325 4575);
PAINT PINK (-8325 4575);
FORCENOTE
TRACE SPACING = 5MIL
(-8925 3850) 0;
DISPLAY LEFT (-8925 3850);
DISPLAY 1.021277 (-8925 3850);
PAINT PINK (-8925 3850);
FORCENOTE
LOCAL SENSE
(-6925 4575) 0;
DISPLAY LEFT (-6925 4575);
DISPLAY 1.021277 (-6925 4575);
PAINT PINK (-6925 4575);
FORCENOTE
TRACE WIDTH = 10MIL
(-8925 3925) 0;
DISPLAY LEFT (-8925 3925);
DISPLAY 1.021277 (-8925 3925);
PAINT PINK (-8925 3925);
FORCENOTE
DIFFERENTIAL PAIR
(-8925 4000) 0;
DISPLAY LEFT (-8925 4000);
DISPLAY 1.021277 (-8925 4000);
PAINT PINK (-8925 4000);
QUIT
